G04*
G04 #@! TF.GenerationSoftware,Altium Limited,Altium Designer,22.4.2 (48)*
G04*
G04 Layer_Color=16711935*
%FSLAX25Y25*%
%MOIN*%
G70*
G04*
G04 #@! TF.SameCoordinates,446674BB-F454-490D-8607-5140536C8ADF*
G04*
G04*
G04 #@! TF.FilePolarity,Negative*
G04*
G01*
G75*
%ADD84R,0.31496X0.13583*%
%ADD85R,1.35433X0.23032*%
%ADD126R,0.03600X0.17300*%
%ADD127R,0.03600X0.13400*%
%ADD133C,0.06706*%
%ADD134R,0.06706X0.06706*%
%ADD135C,0.08300*%
%ADD136C,0.05800*%
%ADD137C,0.10642*%
%ADD138C,0.02966*%
%ADD139R,0.00800X0.00800*%
%ADD140C,0.07398*%
%ADD141C,0.09461*%
%ADD142R,0.08674X0.08674*%
%ADD143C,0.00800*%
%ADD144C,0.25800*%
%ADD145C,0.02400*%
%ADD146C,0.02200*%
%ADD147C,0.20800*%
%ADD148C,0.02769*%
%ADD176R,0.03320X0.03477*%
G36*
X315068Y-7296D02*
X315119Y-7306D01*
X315169Y-7323D01*
X315216Y-7346D01*
X315216Y-7347D01*
X315610D01*
X315663Y-7350D01*
X315714Y-7360D01*
X315764Y-7377D01*
X315811Y-7400D01*
X315811Y-7401D01*
X315827D01*
X315879Y-7404D01*
X315930Y-7414D01*
X315980Y-7431D01*
X316027Y-7455D01*
X316027Y-7455D01*
X316043D01*
X316095Y-7458D01*
X316146Y-7468D01*
X316196Y-7485D01*
X316243Y-7508D01*
X316248Y-7512D01*
X316257Y-7512D01*
X316309Y-7523D01*
X316358Y-7539D01*
X316405Y-7563D01*
X316436Y-7583D01*
X316466Y-7593D01*
X316513Y-7617D01*
X316518Y-7620D01*
X316528Y-7620D01*
X316579Y-7631D01*
X316629Y-7648D01*
X316676Y-7671D01*
X316706Y-7691D01*
X316737Y-7702D01*
X316784Y-7725D01*
X316815Y-7745D01*
X316845Y-7756D01*
X316892Y-7779D01*
X316923Y-7799D01*
X316953Y-7810D01*
X317000Y-7833D01*
X317044Y-7862D01*
X317083Y-7897D01*
X317096Y-7911D01*
X317115Y-7918D01*
X317162Y-7941D01*
X317206Y-7970D01*
X317245Y-8005D01*
X317258Y-8019D01*
X317277Y-8026D01*
X317324Y-8049D01*
X317368Y-8078D01*
X317407Y-8113D01*
X317433Y-8142D01*
X317461Y-8167D01*
X317487Y-8196D01*
X317516Y-8221D01*
X317541Y-8250D01*
X317567Y-8272D01*
X317570Y-8275D01*
X317595Y-8304D01*
X317624Y-8329D01*
X317649Y-8358D01*
X317678Y-8383D01*
X317703Y-8412D01*
X317732Y-8437D01*
X317757Y-8466D01*
X317786Y-8491D01*
X317811Y-8520D01*
X317840Y-8545D01*
X317865Y-8574D01*
X317894Y-8599D01*
X317919Y-8628D01*
X317948Y-8653D01*
X317973Y-8682D01*
X318002Y-8708D01*
X318027Y-8736D01*
X318056Y-8762D01*
X318081Y-8790D01*
X318094Y-8801D01*
X318110Y-8816D01*
X318145Y-8855D01*
X318174Y-8899D01*
X318197Y-8946D01*
X318204Y-8965D01*
X318218Y-8978D01*
X318253Y-9017D01*
X318282Y-9061D01*
X318305Y-9108D01*
X318312Y-9127D01*
X318326Y-9140D01*
X318361Y-9179D01*
X318390Y-9223D01*
X318413Y-9270D01*
X318424Y-9300D01*
X318444Y-9331D01*
X318467Y-9378D01*
X318478Y-9409D01*
X318498Y-9439D01*
X318521Y-9486D01*
X318532Y-9517D01*
X318552Y-9547D01*
X318576Y-9595D01*
X318584Y-9621D01*
X318586Y-9625D01*
X318606Y-9656D01*
X318630Y-9703D01*
X318647Y-9752D01*
X318657Y-9804D01*
X318657Y-9813D01*
X318660Y-9818D01*
X318684Y-9865D01*
X318694Y-9895D01*
X318707Y-9914D01*
X318715Y-9926D01*
X318738Y-9973D01*
X318755Y-10023D01*
X318765Y-10074D01*
X318768Y-10126D01*
Y-10142D01*
X318769Y-10142D01*
X318792Y-10189D01*
X318809Y-10239D01*
X318819Y-10290D01*
X318822Y-10343D01*
Y-10358D01*
X318823Y-10358D01*
X318846Y-10405D01*
X318863Y-10455D01*
X318873Y-10507D01*
X318876Y-10559D01*
Y-10613D01*
Y-10667D01*
Y-10721D01*
Y-10736D01*
X318877Y-10737D01*
X318900Y-10784D01*
X318917Y-10834D01*
X318927Y-10885D01*
X318931Y-10937D01*
Y-10991D01*
Y-11045D01*
Y-11099D01*
Y-11153D01*
Y-11208D01*
Y-11262D01*
Y-11316D01*
Y-11370D01*
Y-11424D01*
Y-11478D01*
Y-11532D01*
Y-11586D01*
Y-11640D01*
X318927Y-11692D01*
X318917Y-11744D01*
X318900Y-11793D01*
X318877Y-11840D01*
X318876Y-11841D01*
Y-11856D01*
Y-11910D01*
X318873Y-11963D01*
X318863Y-12014D01*
X318846Y-12064D01*
X318823Y-12111D01*
X318822Y-12111D01*
Y-12127D01*
Y-12181D01*
X318819Y-12233D01*
X318809Y-12284D01*
X318792Y-12334D01*
X318769Y-12381D01*
X318765Y-12386D01*
X318765Y-12395D01*
X318755Y-12447D01*
X318738Y-12496D01*
X318715Y-12543D01*
X318711Y-12548D01*
X318711Y-12557D01*
X318701Y-12609D01*
X318684Y-12658D01*
X318660Y-12706D01*
X318657Y-12710D01*
X318657Y-12720D01*
X318647Y-12771D01*
X318630Y-12821D01*
X318606Y-12868D01*
X318586Y-12899D01*
X318576Y-12929D01*
X318552Y-12976D01*
X318532Y-13007D01*
X318521Y-13037D01*
X318498Y-13084D01*
X318478Y-13115D01*
X318470Y-13138D01*
X318467Y-13145D01*
X318444Y-13192D01*
X318415Y-13236D01*
X318381Y-13275D01*
X318366Y-13288D01*
X318359Y-13307D01*
X318336Y-13354D01*
X318316Y-13385D01*
X318305Y-13415D01*
X318282Y-13462D01*
X318253Y-13506D01*
X318218Y-13545D01*
X318190Y-13571D01*
X318164Y-13599D01*
X318150Y-13612D01*
X318143Y-13632D01*
X318120Y-13679D01*
X318091Y-13722D01*
X318056Y-13762D01*
X318027Y-13787D01*
X318002Y-13816D01*
X317973Y-13841D01*
X317948Y-13870D01*
X317919Y-13895D01*
X317894Y-13924D01*
X317865Y-13949D01*
X317840Y-13978D01*
X317811Y-14003D01*
X317786Y-14032D01*
X317757Y-14057D01*
X317732Y-14086D01*
X317703Y-14111D01*
X317678Y-14140D01*
X317649Y-14165D01*
X317624Y-14194D01*
X317599Y-14215D01*
X317595Y-14219D01*
X317570Y-14248D01*
X317541Y-14273D01*
X317516Y-14302D01*
X317487Y-14327D01*
X317474Y-14342D01*
X317461Y-14356D01*
X317422Y-14391D01*
X317378Y-14420D01*
X317332Y-14443D01*
X317312Y-14450D01*
X317299Y-14464D01*
X317260Y-14499D01*
X317216Y-14528D01*
X317169Y-14551D01*
X317150Y-14558D01*
X317137Y-14572D01*
X317098Y-14607D01*
X317054Y-14636D01*
X317007Y-14659D01*
X316977Y-14670D01*
X316946Y-14690D01*
X316899Y-14714D01*
X316880Y-14720D01*
X316867Y-14735D01*
X316827Y-14769D01*
X316784Y-14798D01*
X316737Y-14822D01*
X316687Y-14839D01*
X316636Y-14849D01*
X316626Y-14849D01*
X316622Y-14852D01*
X316575Y-14876D01*
X316544Y-14886D01*
X316544D01*
X316513Y-14907D01*
X316466Y-14930D01*
X316417Y-14947D01*
X316365Y-14957D01*
X316356Y-14957D01*
X316351Y-14961D01*
X316304Y-14984D01*
X316255Y-15001D01*
X316203Y-15011D01*
X316194Y-15011D01*
D01*
X316189Y-15015D01*
X316142Y-15038D01*
X316092Y-15055D01*
X316041Y-15065D01*
X316032Y-15066D01*
X316027Y-15069D01*
X315980Y-15092D01*
X315930Y-15109D01*
X315879Y-15119D01*
X315827Y-15122D01*
X315757D01*
X315757Y-15123D01*
X315710Y-15146D01*
X315660Y-15163D01*
X315609Y-15173D01*
X315556Y-15177D01*
X310312D01*
X310260Y-15173D01*
X310208Y-15163D01*
X310159Y-15146D01*
X310112Y-15123D01*
X310111Y-15122D01*
X310042D01*
X309990Y-15119D01*
X309938Y-15109D01*
X309889Y-15092D01*
X309841Y-15069D01*
X309841Y-15068D01*
X309826D01*
X309773Y-15065D01*
X309722Y-15055D01*
X309672Y-15038D01*
X309625Y-15015D01*
X309620Y-15011D01*
X309611Y-15011D01*
X309560Y-15001D01*
X309510Y-14984D01*
X309463Y-14961D01*
X309458Y-14957D01*
X309449Y-14957D01*
X309398Y-14947D01*
X309348Y-14930D01*
X309301Y-14907D01*
X309270Y-14886D01*
X309240Y-14876D01*
X309193Y-14852D01*
X309162Y-14832D01*
X309132Y-14822D01*
X309085Y-14798D01*
X309054Y-14778D01*
X309023Y-14767D01*
X308977Y-14744D01*
X308946Y-14724D01*
X308915Y-14714D01*
X308868Y-14690D01*
X308838Y-14670D01*
X308807Y-14659D01*
X308760Y-14636D01*
X308717Y-14607D01*
X308677Y-14572D01*
X308664Y-14558D01*
X308645Y-14551D01*
X308598Y-14528D01*
X308554Y-14499D01*
X308515Y-14464D01*
X308490Y-14436D01*
X308461Y-14410D01*
X308436Y-14381D01*
X308407Y-14356D01*
X308394Y-14342D01*
X308375Y-14335D01*
X308328Y-14312D01*
X308284Y-14283D01*
X308245Y-14248D01*
X308219Y-14219D01*
X308215Y-14215D01*
X308191Y-14194D01*
X308165Y-14165D01*
X308137Y-14140D01*
X308111Y-14111D01*
X308111Y-14111D01*
X308083Y-14086D01*
X308057Y-14057D01*
X308029Y-14032D01*
X308003Y-14003D01*
X307974Y-13978D01*
X307949Y-13949D01*
X307920Y-13924D01*
X307895Y-13895D01*
X307866Y-13870D01*
X307841Y-13841D01*
X307841Y-13841D01*
X307812Y-13816D01*
X307778Y-13776D01*
X307749Y-13733D01*
X307725Y-13686D01*
X307719Y-13666D01*
X307704Y-13654D01*
X307679Y-13625D01*
X307650Y-13599D01*
X307615Y-13560D01*
X307586Y-13516D01*
X307563Y-13469D01*
X307557Y-13450D01*
X307542Y-13437D01*
X307507Y-13398D01*
X307478Y-13354D01*
X307455Y-13307D01*
X307449Y-13288D01*
X307445Y-13277D01*
X307424Y-13246D01*
X307401Y-13199D01*
X307399Y-13192D01*
X307391Y-13169D01*
X307370Y-13138D01*
X307347Y-13091D01*
X307337Y-13061D01*
X307316Y-13030D01*
X307293Y-12983D01*
X307282Y-12953D01*
X307262Y-12922D01*
X307239Y-12875D01*
X307228Y-12844D01*
X307208Y-12814D01*
X307185Y-12766D01*
X307168Y-12717D01*
X307158Y-12665D01*
X307157Y-12656D01*
X307154Y-12651D01*
X307131Y-12604D01*
X307114Y-12555D01*
X307103Y-12503D01*
X307103Y-12494D01*
X307100Y-12489D01*
X307077Y-12442D01*
X307060Y-12393D01*
X307049Y-12341D01*
X307049Y-12334D01*
X307049Y-12332D01*
X307046Y-12327D01*
X307023Y-12280D01*
X307006Y-12230D01*
X306995Y-12179D01*
X306992Y-12127D01*
Y-12072D01*
Y-12057D01*
X306992Y-12057D01*
X306968Y-12010D01*
X306952Y-11960D01*
X306941Y-11909D01*
X306938Y-11856D01*
Y-11802D01*
Y-11748D01*
Y-11694D01*
Y-11640D01*
Y-11586D01*
Y-11571D01*
X306938Y-11570D01*
X306914Y-11523D01*
X306897Y-11473D01*
X306887Y-11422D01*
X306884Y-11370D01*
Y-11316D01*
Y-11262D01*
Y-11208D01*
Y-11153D01*
X306887Y-11101D01*
X306897Y-11050D01*
X306914Y-11000D01*
X306938Y-10953D01*
X306938Y-10953D01*
Y-10937D01*
Y-10883D01*
Y-10829D01*
Y-10775D01*
Y-10721D01*
Y-10667D01*
Y-10613D01*
X306941Y-10560D01*
X306952Y-10509D01*
X306968Y-10459D01*
X306992Y-10412D01*
X306992Y-10412D01*
Y-10397D01*
X306995Y-10344D01*
X307006Y-10293D01*
X307023Y-10243D01*
X307046Y-10196D01*
X307046Y-10196D01*
Y-10180D01*
X307049Y-10128D01*
X307060Y-10077D01*
X307077Y-10027D01*
X307100Y-9980D01*
X307103Y-9975D01*
X307103Y-9966D01*
X307114Y-9914D01*
X307131Y-9865D01*
X307154Y-9818D01*
X307174Y-9787D01*
X307185Y-9757D01*
X307208Y-9710D01*
X307211Y-9705D01*
X307212Y-9696D01*
X307222Y-9644D01*
X307239Y-9595D01*
X307262Y-9547D01*
X307282Y-9517D01*
X307293Y-9486D01*
X307316Y-9439D01*
X307345Y-9396D01*
X307380Y-9356D01*
X307394Y-9343D01*
X307401Y-9324D01*
X307424Y-9277D01*
X307445Y-9246D01*
X307455Y-9216D01*
X307478Y-9169D01*
X307507Y-9125D01*
X307542Y-9086D01*
X307545Y-9083D01*
X307557Y-9073D01*
X307563Y-9054D01*
X307586Y-9007D01*
X307615Y-8963D01*
X307650Y-8924D01*
X307665Y-8911D01*
X307671Y-8892D01*
X307694Y-8845D01*
X307724Y-8801D01*
X307758Y-8762D01*
X307787Y-8736D01*
X307812Y-8708D01*
X307841Y-8682D01*
X307866Y-8653D01*
X307895Y-8628D01*
X307920Y-8599D01*
X307949Y-8574D01*
X307974Y-8545D01*
X308003Y-8520D01*
X308029Y-8491D01*
X308057Y-8466D01*
X308083Y-8437D01*
X308111Y-8412D01*
X308137Y-8383D01*
X308165Y-8358D01*
X308191Y-8329D01*
X308219Y-8304D01*
X308245Y-8275D01*
X308274Y-8250D01*
X308299Y-8221D01*
X308328Y-8196D01*
X308353Y-8167D01*
X308392Y-8132D01*
X308436Y-8103D01*
X308483Y-8080D01*
X308502Y-8073D01*
X308515Y-8059D01*
X308554Y-8024D01*
X308598Y-7995D01*
X308645Y-7972D01*
X308664Y-7965D01*
X308677Y-7951D01*
X308717Y-7916D01*
X308760Y-7887D01*
X308807Y-7864D01*
X308838Y-7853D01*
X308868Y-7833D01*
X308915Y-7810D01*
X308935Y-7803D01*
X308947Y-7789D01*
X308987Y-7754D01*
X309031Y-7725D01*
X309078Y-7702D01*
X309127Y-7685D01*
X309179Y-7675D01*
X309188Y-7674D01*
X309193Y-7671D01*
X309240Y-7648D01*
X309270Y-7637D01*
X309301Y-7617D01*
X309348Y-7593D01*
X309398Y-7577D01*
X309449Y-7566D01*
X309458Y-7566D01*
X309463Y-7563D01*
X309510Y-7539D01*
X309540Y-7529D01*
X309571Y-7508D01*
X309618Y-7485D01*
X309668Y-7468D01*
X309719Y-7458D01*
X309772Y-7455D01*
X309787D01*
X309787Y-7455D01*
X309834Y-7431D01*
X309884Y-7414D01*
X309935Y-7404D01*
X309988Y-7401D01*
X310057D01*
X310058Y-7400D01*
X310105Y-7377D01*
X310154Y-7360D01*
X310206Y-7350D01*
X310258Y-7347D01*
X310598D01*
X310598Y-7346D01*
X310645Y-7323D01*
X310695Y-7306D01*
X310746Y-7296D01*
X310799Y-7293D01*
X310853D01*
X310880Y-7294D01*
X310907Y-7293D01*
X315016D01*
X315068Y-7296D01*
D02*
G37*
G36*
X395350D02*
X395401Y-7306D01*
X395451Y-7323D01*
X395498Y-7346D01*
X395542Y-7376D01*
X395581Y-7410D01*
X395606Y-7439D01*
X395635Y-7464D01*
X395670Y-7503D01*
X395699Y-7547D01*
X395722Y-7594D01*
X395739Y-7644D01*
X395749Y-7695D01*
X395753Y-7748D01*
Y-7802D01*
Y-7856D01*
Y-7910D01*
Y-7964D01*
Y-8018D01*
Y-8072D01*
Y-8126D01*
Y-8180D01*
Y-8234D01*
Y-8288D01*
Y-8342D01*
Y-8396D01*
Y-8450D01*
Y-8504D01*
Y-8558D01*
Y-8613D01*
Y-8667D01*
Y-8721D01*
Y-8775D01*
Y-8829D01*
Y-8883D01*
Y-8937D01*
Y-8991D01*
Y-9045D01*
Y-9099D01*
Y-9153D01*
Y-9207D01*
Y-9261D01*
Y-9315D01*
Y-9369D01*
Y-9424D01*
Y-9478D01*
Y-9532D01*
Y-9586D01*
Y-9640D01*
Y-9694D01*
Y-9748D01*
Y-9802D01*
Y-9856D01*
Y-9910D01*
Y-9964D01*
Y-10018D01*
Y-10072D01*
Y-10126D01*
Y-10180D01*
Y-10234D01*
Y-10289D01*
Y-10343D01*
Y-10397D01*
Y-10451D01*
Y-10505D01*
Y-10559D01*
Y-10613D01*
Y-10667D01*
Y-10721D01*
Y-10775D01*
Y-10829D01*
Y-10883D01*
Y-10937D01*
D01*
Y-10991D01*
Y-11045D01*
Y-11099D01*
Y-11153D01*
Y-11208D01*
Y-11262D01*
Y-11316D01*
Y-11370D01*
Y-11424D01*
Y-11478D01*
Y-11532D01*
Y-11586D01*
Y-11640D01*
Y-11694D01*
Y-11748D01*
Y-11802D01*
Y-11856D01*
Y-11910D01*
Y-11964D01*
Y-12019D01*
Y-12072D01*
Y-12127D01*
Y-12181D01*
Y-12235D01*
Y-12289D01*
Y-12343D01*
Y-12397D01*
Y-12451D01*
Y-12505D01*
Y-12559D01*
Y-12613D01*
Y-12667D01*
Y-12721D01*
Y-12775D01*
Y-12829D01*
Y-12883D01*
Y-12937D01*
Y-12992D01*
Y-13046D01*
Y-13100D01*
Y-13154D01*
Y-13208D01*
Y-13262D01*
Y-13316D01*
Y-13370D01*
Y-13424D01*
Y-13478D01*
Y-13532D01*
Y-13586D01*
Y-13640D01*
Y-13694D01*
Y-13748D01*
Y-13803D01*
Y-13857D01*
Y-13911D01*
Y-13965D01*
Y-14019D01*
Y-14073D01*
Y-14127D01*
Y-14181D01*
Y-14235D01*
Y-14289D01*
Y-14343D01*
Y-14397D01*
Y-14451D01*
Y-14505D01*
Y-14559D01*
Y-14614D01*
Y-14668D01*
Y-14722D01*
Y-14776D01*
Y-14830D01*
Y-14884D01*
Y-14938D01*
Y-14992D01*
Y-15046D01*
Y-15100D01*
Y-15154D01*
Y-15208D01*
Y-15262D01*
Y-15316D01*
Y-15370D01*
Y-15424D01*
Y-15478D01*
Y-15532D01*
Y-15587D01*
Y-15641D01*
Y-15695D01*
Y-15749D01*
Y-15803D01*
Y-15857D01*
Y-15911D01*
Y-15965D01*
Y-16019D01*
Y-16073D01*
Y-16127D01*
Y-16181D01*
Y-16235D01*
Y-16289D01*
Y-16343D01*
Y-16398D01*
Y-16452D01*
Y-16506D01*
Y-16560D01*
Y-16614D01*
Y-16668D01*
Y-16722D01*
Y-16776D01*
Y-16830D01*
Y-16884D01*
Y-16938D01*
Y-16992D01*
Y-17046D01*
Y-17100D01*
Y-17154D01*
Y-17208D01*
Y-17263D01*
Y-17317D01*
Y-17371D01*
Y-17425D01*
Y-17479D01*
Y-17533D01*
Y-17587D01*
Y-17641D01*
Y-17695D01*
Y-17749D01*
Y-17803D01*
Y-17857D01*
Y-17911D01*
Y-17965D01*
Y-18019D01*
Y-18073D01*
Y-18127D01*
Y-18181D01*
Y-18236D01*
Y-18290D01*
Y-18344D01*
Y-18398D01*
Y-18452D01*
Y-18506D01*
Y-18560D01*
Y-18614D01*
Y-18668D01*
Y-18722D01*
Y-18776D01*
Y-18830D01*
Y-18884D01*
Y-18938D01*
Y-18993D01*
Y-19047D01*
Y-19101D01*
Y-19155D01*
Y-19209D01*
Y-19263D01*
Y-19317D01*
Y-19371D01*
Y-19425D01*
Y-19479D01*
Y-19533D01*
Y-19587D01*
Y-19641D01*
Y-19695D01*
Y-19749D01*
Y-19803D01*
Y-19858D01*
Y-19911D01*
Y-19966D01*
Y-20020D01*
Y-20074D01*
Y-20128D01*
Y-20182D01*
Y-20236D01*
Y-20290D01*
Y-20344D01*
Y-20398D01*
Y-20452D01*
Y-20506D01*
Y-20560D01*
Y-20614D01*
Y-20668D01*
Y-20722D01*
Y-20776D01*
Y-20831D01*
Y-20885D01*
Y-20939D01*
Y-20993D01*
Y-21047D01*
Y-21101D01*
Y-21155D01*
Y-21209D01*
Y-21263D01*
Y-21317D01*
Y-21371D01*
Y-21425D01*
Y-21479D01*
Y-21533D01*
Y-21587D01*
Y-21642D01*
Y-21696D01*
Y-21750D01*
Y-21804D01*
Y-21858D01*
Y-21912D01*
Y-21966D01*
Y-22020D01*
Y-22074D01*
Y-22128D01*
Y-22182D01*
Y-22236D01*
Y-22290D01*
Y-22344D01*
Y-22398D01*
Y-22452D01*
Y-22506D01*
Y-22561D01*
Y-22615D01*
Y-22669D01*
Y-22723D01*
Y-22777D01*
Y-22831D01*
Y-22885D01*
Y-22939D01*
Y-22993D01*
Y-23047D01*
Y-23101D01*
Y-23155D01*
Y-23209D01*
Y-23263D01*
Y-23317D01*
Y-23371D01*
Y-23426D01*
Y-23480D01*
Y-23534D01*
Y-23588D01*
Y-23642D01*
Y-23696D01*
Y-23750D01*
Y-23804D01*
Y-23858D01*
Y-23912D01*
Y-23966D01*
Y-24020D01*
Y-24074D01*
Y-24128D01*
Y-24182D01*
Y-24237D01*
Y-24291D01*
Y-24345D01*
Y-24399D01*
Y-24453D01*
Y-24507D01*
Y-24561D01*
Y-24615D01*
Y-24669D01*
Y-24723D01*
Y-24777D01*
Y-24831D01*
Y-24885D01*
Y-24939D01*
Y-24993D01*
Y-25047D01*
Y-25102D01*
Y-25155D01*
Y-25210D01*
Y-25264D01*
Y-25318D01*
Y-25372D01*
Y-25426D01*
Y-25480D01*
Y-25534D01*
Y-25588D01*
Y-25642D01*
Y-25696D01*
Y-25750D01*
Y-25804D01*
Y-25858D01*
Y-25912D01*
Y-25967D01*
Y-26021D01*
Y-26075D01*
Y-26129D01*
Y-26183D01*
Y-26237D01*
Y-26291D01*
Y-26345D01*
Y-26399D01*
Y-26453D01*
Y-26507D01*
Y-26561D01*
Y-26615D01*
Y-26669D01*
Y-26723D01*
Y-26777D01*
Y-26831D01*
Y-26886D01*
Y-26940D01*
Y-26994D01*
Y-27048D01*
Y-27102D01*
Y-27156D01*
Y-27210D01*
Y-27264D01*
Y-27318D01*
Y-27372D01*
Y-27426D01*
Y-27480D01*
Y-27534D01*
Y-27588D01*
Y-27642D01*
Y-27696D01*
Y-27751D01*
Y-27805D01*
Y-27859D01*
Y-27913D01*
Y-27967D01*
Y-28021D01*
Y-28075D01*
Y-28129D01*
Y-28183D01*
Y-28237D01*
Y-28291D01*
Y-28345D01*
Y-28399D01*
Y-28453D01*
Y-28507D01*
Y-28561D01*
Y-28615D01*
Y-28670D01*
Y-28724D01*
Y-28778D01*
Y-28832D01*
Y-28886D01*
Y-28940D01*
Y-28994D01*
Y-29048D01*
Y-29102D01*
Y-29156D01*
Y-29210D01*
Y-29264D01*
Y-29318D01*
X395749Y-29371D01*
X395739Y-29422D01*
X395722Y-29472D01*
X395699Y-29519D01*
X395670Y-29562D01*
X395635Y-29602D01*
X395596Y-29636D01*
X395552Y-29665D01*
X395505Y-29689D01*
X395456Y-29706D01*
X395404Y-29716D01*
X395352Y-29719D01*
X390509D01*
Y-29751D01*
Y-29805D01*
Y-29859D01*
Y-29913D01*
Y-29967D01*
Y-30021D01*
Y-30075D01*
Y-30129D01*
Y-30183D01*
Y-30237D01*
Y-30291D01*
Y-30345D01*
Y-30400D01*
Y-30454D01*
Y-30508D01*
Y-30562D01*
Y-30616D01*
Y-30670D01*
Y-30724D01*
Y-30778D01*
Y-30832D01*
Y-30886D01*
Y-30940D01*
Y-30994D01*
Y-31048D01*
Y-31102D01*
Y-31156D01*
Y-31211D01*
Y-31265D01*
Y-31319D01*
Y-31373D01*
Y-31427D01*
Y-31481D01*
Y-31535D01*
Y-31589D01*
Y-31643D01*
Y-31697D01*
Y-31751D01*
Y-31805D01*
Y-31859D01*
Y-31913D01*
Y-31967D01*
Y-32021D01*
Y-32076D01*
Y-32129D01*
Y-32184D01*
D01*
Y-32238D01*
Y-32292D01*
Y-32346D01*
Y-32400D01*
Y-32454D01*
Y-32508D01*
Y-32562D01*
Y-32616D01*
Y-32670D01*
Y-32724D01*
Y-32778D01*
Y-32832D01*
Y-32886D01*
Y-32941D01*
Y-32994D01*
Y-33049D01*
Y-33103D01*
Y-33157D01*
Y-33211D01*
Y-33265D01*
Y-33319D01*
Y-33373D01*
Y-33427D01*
Y-33481D01*
Y-33535D01*
Y-33589D01*
Y-33643D01*
Y-33697D01*
Y-33751D01*
Y-33806D01*
Y-33860D01*
Y-33914D01*
Y-33968D01*
Y-34022D01*
Y-34076D01*
Y-34130D01*
Y-34184D01*
Y-34238D01*
Y-34292D01*
Y-34346D01*
Y-34400D01*
Y-34454D01*
Y-34508D01*
Y-34562D01*
Y-34616D01*
Y-34670D01*
Y-34725D01*
Y-34779D01*
Y-34833D01*
Y-34864D01*
X395298D01*
X395350Y-34868D01*
X395401Y-34878D01*
X395451Y-34895D01*
X395498Y-34918D01*
X395542Y-34947D01*
X395581Y-34982D01*
X395587Y-34988D01*
X395606Y-35010D01*
X395635Y-35036D01*
X395670Y-35075D01*
X395699Y-35119D01*
X395722Y-35166D01*
X395739Y-35215D01*
X395749Y-35267D01*
X395753Y-35319D01*
Y-35373D01*
Y-35427D01*
Y-35481D01*
Y-35535D01*
Y-35590D01*
Y-35644D01*
Y-35698D01*
Y-35752D01*
Y-35806D01*
Y-35860D01*
Y-35914D01*
Y-35968D01*
Y-36022D01*
Y-36076D01*
Y-36130D01*
Y-36184D01*
Y-36238D01*
Y-36292D01*
Y-36346D01*
Y-36400D01*
Y-36454D01*
Y-36509D01*
Y-36563D01*
Y-36617D01*
X395749Y-36669D01*
X395739Y-36720D01*
X395722Y-36770D01*
X395699Y-36817D01*
X395670Y-36861D01*
X395635Y-36900D01*
X395596Y-36935D01*
X395552Y-36964D01*
X395505Y-36987D01*
X395456Y-37004D01*
X395404Y-37014D01*
X395352Y-37018D01*
X390509D01*
Y-37049D01*
Y-37103D01*
Y-37157D01*
Y-37211D01*
Y-37265D01*
Y-37319D01*
Y-37374D01*
Y-37428D01*
Y-37482D01*
Y-37536D01*
Y-37590D01*
Y-37644D01*
Y-37698D01*
Y-37752D01*
Y-37806D01*
Y-37860D01*
Y-37914D01*
Y-37968D01*
Y-38022D01*
Y-38076D01*
Y-38130D01*
Y-38184D01*
Y-38238D01*
Y-38293D01*
Y-38347D01*
Y-38401D01*
Y-38455D01*
Y-38509D01*
Y-38563D01*
Y-38617D01*
Y-38671D01*
Y-38725D01*
Y-38779D01*
Y-38833D01*
Y-38887D01*
Y-38941D01*
Y-38995D01*
Y-39050D01*
Y-39103D01*
Y-39158D01*
Y-39212D01*
Y-39266D01*
Y-39320D01*
Y-39374D01*
Y-39428D01*
Y-39482D01*
Y-39536D01*
Y-39590D01*
Y-39644D01*
Y-39698D01*
Y-39752D01*
Y-39806D01*
Y-39860D01*
Y-39915D01*
Y-39968D01*
Y-40023D01*
Y-40077D01*
Y-40131D01*
Y-40185D01*
Y-40239D01*
Y-40293D01*
Y-40347D01*
Y-40401D01*
Y-40455D01*
Y-40509D01*
Y-40563D01*
Y-40617D01*
Y-40671D01*
Y-40725D01*
Y-40780D01*
Y-40834D01*
Y-40888D01*
Y-40942D01*
Y-40996D01*
Y-41050D01*
Y-41104D01*
Y-41158D01*
Y-41212D01*
Y-41266D01*
Y-41320D01*
Y-41374D01*
Y-41428D01*
Y-41482D01*
Y-41536D01*
Y-41590D01*
Y-41644D01*
Y-41699D01*
Y-41753D01*
Y-41807D01*
Y-41861D01*
Y-41915D01*
Y-41969D01*
Y-42023D01*
Y-42077D01*
Y-42131D01*
Y-42185D01*
Y-42217D01*
X395352D01*
X395404Y-42220D01*
X395456Y-42230D01*
X395505Y-42247D01*
X395552Y-42270D01*
X395596Y-42300D01*
X395635Y-42334D01*
X395670Y-42373D01*
X395699Y-42417D01*
X395722Y-42464D01*
X395739Y-42514D01*
X395749Y-42565D01*
X395753Y-42618D01*
Y-42672D01*
Y-42726D01*
Y-42780D01*
Y-42834D01*
Y-42888D01*
Y-42942D01*
Y-42996D01*
Y-43050D01*
Y-43104D01*
Y-43158D01*
Y-43212D01*
Y-43266D01*
Y-43320D01*
Y-43374D01*
Y-43429D01*
Y-43483D01*
Y-43537D01*
Y-43591D01*
Y-43645D01*
Y-43699D01*
Y-43753D01*
Y-43807D01*
Y-43861D01*
Y-43915D01*
X395749Y-43967D01*
X395739Y-44019D01*
X395722Y-44069D01*
X395699Y-44115D01*
X395670Y-44159D01*
X395635Y-44199D01*
X395606Y-44224D01*
X395581Y-44253D01*
X395542Y-44287D01*
X395498Y-44316D01*
X395451Y-44339D01*
X395401Y-44356D01*
X395350Y-44367D01*
X395298Y-44370D01*
X390509D01*
Y-44402D01*
Y-44456D01*
Y-44510D01*
Y-44564D01*
Y-44618D01*
Y-44672D01*
Y-44726D01*
Y-44780D01*
Y-44834D01*
Y-44888D01*
Y-44942D01*
Y-44996D01*
Y-45050D01*
Y-45104D01*
Y-45158D01*
Y-45213D01*
Y-45267D01*
Y-45321D01*
Y-45375D01*
Y-45429D01*
Y-45483D01*
Y-45537D01*
Y-45591D01*
Y-45645D01*
Y-45699D01*
Y-45753D01*
Y-45807D01*
Y-45861D01*
Y-45915D01*
Y-45969D01*
Y-46023D01*
Y-46077D01*
Y-46132D01*
Y-46186D01*
Y-46240D01*
Y-46294D01*
Y-46348D01*
Y-46402D01*
Y-46456D01*
Y-46510D01*
Y-46564D01*
Y-46618D01*
Y-46672D01*
Y-46726D01*
Y-46780D01*
Y-46834D01*
Y-46889D01*
Y-46942D01*
Y-46997D01*
Y-47051D01*
Y-47105D01*
Y-47159D01*
Y-47213D01*
Y-47267D01*
Y-47321D01*
Y-47375D01*
Y-47429D01*
Y-47483D01*
Y-47537D01*
Y-47591D01*
Y-47645D01*
Y-47699D01*
Y-47754D01*
Y-47807D01*
Y-47862D01*
Y-47916D01*
Y-47970D01*
Y-48024D01*
Y-48078D01*
Y-48132D01*
Y-48186D01*
Y-48240D01*
Y-48294D01*
Y-48348D01*
Y-48402D01*
Y-48456D01*
Y-48510D01*
Y-48564D01*
Y-48619D01*
Y-48673D01*
Y-48727D01*
Y-48781D01*
Y-48835D01*
Y-48889D01*
Y-48943D01*
Y-48997D01*
Y-49051D01*
Y-49105D01*
Y-49159D01*
Y-49213D01*
Y-49267D01*
Y-49321D01*
Y-49375D01*
Y-49429D01*
Y-49483D01*
Y-49515D01*
X395352D01*
X395404Y-49518D01*
X395456Y-49529D01*
X395505Y-49546D01*
X395552Y-49569D01*
X395596Y-49598D01*
X395635Y-49632D01*
X395670Y-49672D01*
X395699Y-49716D01*
X395722Y-49762D01*
X395739Y-49812D01*
X395749Y-49864D01*
X395753Y-49916D01*
Y-49970D01*
Y-50024D01*
Y-50078D01*
Y-50132D01*
Y-50186D01*
Y-50240D01*
Y-50294D01*
Y-50348D01*
Y-50402D01*
Y-50457D01*
Y-50511D01*
Y-50565D01*
Y-50619D01*
Y-50673D01*
Y-50727D01*
Y-50781D01*
Y-50835D01*
Y-50889D01*
Y-50943D01*
Y-50997D01*
Y-51051D01*
Y-51105D01*
Y-51159D01*
Y-51213D01*
Y-51267D01*
X395749Y-51320D01*
X395739Y-51371D01*
X395722Y-51421D01*
X395699Y-51468D01*
X395670Y-51512D01*
X395635Y-51551D01*
X395596Y-51586D01*
X395552Y-51615D01*
X395505Y-51638D01*
X395456Y-51655D01*
X395404Y-51665D01*
X395352Y-51668D01*
X390509D01*
Y-51700D01*
Y-51754D01*
Y-51808D01*
Y-51862D01*
Y-51916D01*
Y-51970D01*
Y-52024D01*
Y-52078D01*
Y-52132D01*
Y-52187D01*
Y-52241D01*
Y-52295D01*
Y-52349D01*
Y-52403D01*
Y-52457D01*
Y-52511D01*
Y-52565D01*
Y-52619D01*
Y-52673D01*
Y-52727D01*
Y-52781D01*
Y-52835D01*
Y-52889D01*
Y-52943D01*
Y-52997D01*
Y-53052D01*
Y-53106D01*
Y-53160D01*
Y-53214D01*
Y-53268D01*
Y-53322D01*
Y-53376D01*
Y-53430D01*
Y-53484D01*
Y-53538D01*
Y-53592D01*
Y-53646D01*
Y-53700D01*
Y-53754D01*
Y-53808D01*
Y-53863D01*
Y-53917D01*
Y-53971D01*
Y-54025D01*
Y-54079D01*
Y-54133D01*
Y-54187D01*
Y-54241D01*
Y-54295D01*
Y-54349D01*
Y-54403D01*
Y-54457D01*
Y-54511D01*
Y-54565D01*
Y-54619D01*
Y-54673D01*
Y-54728D01*
Y-54782D01*
Y-54836D01*
Y-54890D01*
Y-54944D01*
Y-54998D01*
Y-55052D01*
Y-55106D01*
Y-55160D01*
Y-55214D01*
Y-55268D01*
Y-55322D01*
Y-55376D01*
Y-55430D01*
Y-55484D01*
Y-55538D01*
Y-55592D01*
Y-55647D01*
Y-55701D01*
Y-55755D01*
Y-55809D01*
Y-55863D01*
Y-55917D01*
Y-55971D01*
Y-56025D01*
Y-56079D01*
Y-56133D01*
Y-56187D01*
Y-56241D01*
Y-56295D01*
Y-56349D01*
Y-56403D01*
Y-56457D01*
Y-56511D01*
Y-56566D01*
Y-56620D01*
Y-56674D01*
Y-56728D01*
Y-56782D01*
Y-56814D01*
X395352D01*
X395404Y-56817D01*
X395456Y-56827D01*
X395505Y-56844D01*
X395552Y-56867D01*
X395596Y-56896D01*
X395635Y-56931D01*
X395670Y-56970D01*
X395699Y-57014D01*
X395722Y-57061D01*
X395739Y-57111D01*
X395749Y-57162D01*
X395753Y-57214D01*
Y-57268D01*
Y-57322D01*
Y-57376D01*
Y-57431D01*
Y-57485D01*
Y-57539D01*
Y-57593D01*
Y-57647D01*
Y-57701D01*
Y-57755D01*
Y-57809D01*
Y-57863D01*
Y-57917D01*
Y-57971D01*
Y-58025D01*
Y-58079D01*
Y-58133D01*
Y-58187D01*
Y-58241D01*
Y-58296D01*
Y-58350D01*
Y-58404D01*
Y-58458D01*
Y-58512D01*
Y-58566D01*
Y-58620D01*
Y-58674D01*
Y-58728D01*
Y-58782D01*
Y-58836D01*
Y-58890D01*
Y-58944D01*
Y-58998D01*
Y-59052D01*
Y-59106D01*
Y-59161D01*
Y-59215D01*
Y-59269D01*
Y-59323D01*
Y-59377D01*
Y-59431D01*
Y-59485D01*
Y-59539D01*
Y-59593D01*
Y-59647D01*
Y-59701D01*
Y-59755D01*
Y-59809D01*
Y-59863D01*
Y-59917D01*
Y-59971D01*
Y-60026D01*
Y-60080D01*
Y-60134D01*
Y-60188D01*
Y-60242D01*
Y-60296D01*
Y-60350D01*
Y-60404D01*
Y-60458D01*
Y-60512D01*
Y-60566D01*
Y-60620D01*
Y-60674D01*
Y-60728D01*
Y-60782D01*
Y-60836D01*
Y-60891D01*
Y-60945D01*
Y-60999D01*
Y-61053D01*
Y-61107D01*
Y-61161D01*
Y-61215D01*
Y-61269D01*
Y-61323D01*
Y-61377D01*
Y-61431D01*
Y-61485D01*
Y-61539D01*
Y-61593D01*
Y-61647D01*
Y-61702D01*
Y-61756D01*
Y-61810D01*
Y-61864D01*
Y-61918D01*
Y-61972D01*
Y-62026D01*
Y-62080D01*
X395749Y-62132D01*
X395739Y-62184D01*
X395722Y-62233D01*
X395699Y-62280D01*
X395670Y-62324D01*
X395635Y-62363D01*
X395596Y-62398D01*
X395552Y-62427D01*
X395505Y-62450D01*
X395456Y-62467D01*
X395404Y-62477D01*
X395352Y-62481D01*
X387297D01*
X387244Y-62477D01*
X387193Y-62467D01*
X387143Y-62450D01*
X387096Y-62427D01*
X387052Y-62398D01*
X387013Y-62363D01*
X386979Y-62324D01*
X386949Y-62280D01*
X386926Y-62233D01*
X386909Y-62184D01*
X386899Y-62132D01*
X386896Y-62080D01*
Y-62026D01*
Y-61972D01*
Y-61918D01*
Y-61864D01*
Y-61810D01*
Y-61756D01*
Y-61702D01*
Y-61647D01*
Y-61593D01*
Y-61539D01*
Y-61485D01*
Y-61431D01*
Y-61377D01*
Y-61323D01*
Y-61269D01*
Y-61215D01*
Y-61161D01*
Y-61107D01*
Y-61053D01*
Y-60999D01*
Y-60945D01*
Y-60891D01*
Y-60836D01*
Y-60782D01*
Y-60728D01*
Y-60674D01*
Y-60620D01*
Y-60566D01*
Y-60512D01*
Y-60458D01*
Y-60404D01*
Y-60350D01*
Y-60296D01*
Y-60242D01*
Y-60188D01*
Y-60134D01*
Y-60080D01*
Y-60026D01*
Y-59971D01*
Y-59917D01*
Y-59863D01*
Y-59809D01*
Y-59755D01*
Y-59701D01*
Y-59647D01*
Y-59593D01*
Y-59539D01*
Y-59485D01*
Y-59431D01*
Y-59377D01*
Y-59323D01*
Y-59269D01*
Y-59215D01*
Y-59161D01*
Y-59106D01*
Y-59052D01*
Y-58998D01*
Y-58944D01*
Y-58890D01*
Y-58836D01*
Y-58782D01*
Y-58728D01*
Y-58674D01*
Y-58620D01*
Y-58566D01*
Y-58512D01*
Y-58458D01*
Y-58404D01*
Y-58350D01*
Y-58296D01*
Y-58241D01*
Y-58187D01*
Y-58133D01*
Y-58079D01*
Y-58025D01*
Y-57971D01*
Y-57917D01*
Y-57863D01*
Y-57809D01*
Y-57755D01*
Y-57701D01*
Y-57647D01*
Y-57593D01*
Y-57577D01*
X386895Y-57577D01*
X386872Y-57530D01*
X386866Y-57512D01*
X386865Y-57511D01*
X386851Y-57498D01*
X386838Y-57483D01*
X386819Y-57477D01*
X386772Y-57453D01*
X386771Y-57453D01*
X378794D01*
X378793Y-57453D01*
X378746Y-57477D01*
X378716Y-57487D01*
X378685Y-57507D01*
X378675Y-57512D01*
X378669Y-57523D01*
X378669Y-57523D01*
Y-57539D01*
Y-57593D01*
Y-57647D01*
X378667Y-57674D01*
X378669Y-57701D01*
Y-57755D01*
X378666Y-57807D01*
X378665Y-57809D01*
X378666Y-57811D01*
X378669Y-57863D01*
Y-57917D01*
Y-57971D01*
Y-58025D01*
Y-58079D01*
Y-58133D01*
Y-58187D01*
Y-58241D01*
Y-58296D01*
Y-58350D01*
Y-58404D01*
Y-58458D01*
Y-58512D01*
Y-58566D01*
Y-58620D01*
Y-58674D01*
Y-58728D01*
Y-58782D01*
Y-58836D01*
Y-58890D01*
Y-58944D01*
Y-58998D01*
Y-59052D01*
Y-59106D01*
Y-59161D01*
Y-59215D01*
Y-59269D01*
Y-59323D01*
Y-59377D01*
Y-59431D01*
Y-59485D01*
Y-59539D01*
Y-59593D01*
Y-59647D01*
Y-59701D01*
Y-59755D01*
Y-59809D01*
Y-59863D01*
Y-59917D01*
Y-59971D01*
Y-60026D01*
Y-60080D01*
Y-60134D01*
Y-60188D01*
Y-60242D01*
Y-60296D01*
Y-60350D01*
Y-60404D01*
Y-60458D01*
Y-60512D01*
Y-60566D01*
Y-60620D01*
X378666Y-60672D01*
X378655Y-60724D01*
X378639Y-60774D01*
X378615Y-60821D01*
X378612Y-60825D01*
X378612Y-60832D01*
X378611Y-60835D01*
X378601Y-60886D01*
X378584Y-60936D01*
X378561Y-60983D01*
X378532Y-61026D01*
X378498Y-61066D01*
X378469Y-61091D01*
X378444Y-61120D01*
X378415Y-61145D01*
X378389Y-61174D01*
X378361Y-61199D01*
X378335Y-61228D01*
X378307Y-61253D01*
X378281Y-61282D01*
X378242Y-61317D01*
X378198Y-61346D01*
X378151Y-61369D01*
X378102Y-61386D01*
X378050Y-61396D01*
X378041Y-61397D01*
X378036Y-61400D01*
X377989Y-61423D01*
X377939Y-61440D01*
X377888Y-61450D01*
X377836Y-61454D01*
X374592D01*
X374540Y-61450D01*
X374488Y-61440D01*
X374439Y-61423D01*
X374392Y-61400D01*
X374391Y-61400D01*
X374387Y-61397D01*
X374377Y-61396D01*
X374326Y-61386D01*
X374276Y-61369D01*
X374229Y-61346D01*
X374186Y-61317D01*
X374146Y-61282D01*
X374121Y-61253D01*
X374092Y-61228D01*
X374067Y-61199D01*
X374038Y-61174D01*
X374013Y-61145D01*
X373984Y-61120D01*
X373959Y-61091D01*
X373930Y-61066D01*
X373896Y-61026D01*
X373866Y-60983D01*
X373843Y-60936D01*
X373826Y-60886D01*
X373816Y-60835D01*
X373813Y-60782D01*
Y-60767D01*
X373812Y-60767D01*
X373789Y-60720D01*
X373772Y-60670D01*
X373762Y-60619D01*
X373759Y-60566D01*
Y-60512D01*
Y-60458D01*
Y-60404D01*
Y-60350D01*
Y-60296D01*
Y-60242D01*
Y-60188D01*
Y-60134D01*
Y-60080D01*
Y-60026D01*
Y-59971D01*
Y-59917D01*
Y-59863D01*
Y-59809D01*
Y-59755D01*
Y-59701D01*
Y-59647D01*
Y-59593D01*
Y-59539D01*
Y-59485D01*
Y-59431D01*
Y-59377D01*
Y-59323D01*
Y-59269D01*
Y-59215D01*
Y-59161D01*
Y-59106D01*
Y-59052D01*
Y-58998D01*
Y-58944D01*
Y-58890D01*
Y-58836D01*
Y-58782D01*
Y-58728D01*
Y-58674D01*
Y-58620D01*
Y-58566D01*
Y-58512D01*
Y-58458D01*
Y-58404D01*
Y-58350D01*
Y-58296D01*
Y-58241D01*
X373760Y-58214D01*
X373759Y-58187D01*
Y-58133D01*
Y-58079D01*
X373760Y-58052D01*
X373759Y-58025D01*
Y-57971D01*
Y-57917D01*
Y-57902D01*
X373758Y-57901D01*
X373735Y-57854D01*
X373725Y-57825D01*
X373725Y-57824D01*
X373704Y-57793D01*
X373681Y-57746D01*
X373675Y-57728D01*
X373674Y-57727D01*
X373660Y-57714D01*
X373635Y-57685D01*
X373606Y-57660D01*
X373580Y-57631D01*
X373552Y-57606D01*
X373539Y-57591D01*
X373519Y-57585D01*
X373472Y-57561D01*
X373451Y-57547D01*
X373442Y-57541D01*
X373411Y-57531D01*
X373364Y-57507D01*
X373364Y-57507D01*
X373360Y-57504D01*
X373350Y-57504D01*
X373299Y-57493D01*
X373249Y-57477D01*
X373202Y-57453D01*
X373202Y-57453D01*
X373171D01*
X373170Y-57453D01*
X373124Y-57477D01*
X373074Y-57493D01*
X373022Y-57504D01*
X373013Y-57504D01*
X373008Y-57507D01*
X372961Y-57531D01*
X372931Y-57541D01*
X372921Y-57547D01*
X372900Y-57561D01*
X372853Y-57585D01*
X372834Y-57591D01*
X372821Y-57606D01*
X372792Y-57631D01*
X372767Y-57660D01*
X372752Y-57673D01*
X372746Y-57692D01*
X372723Y-57739D01*
X372702Y-57770D01*
X372698Y-57782D01*
X372692Y-57800D01*
X372669Y-57847D01*
X372648Y-57878D01*
X372642Y-57894D01*
X372638Y-57908D01*
X372614Y-57955D01*
X372614Y-57956D01*
Y-57971D01*
Y-58025D01*
Y-58079D01*
Y-58133D01*
Y-58187D01*
Y-58241D01*
X372612Y-58268D01*
X372614Y-58296D01*
Y-58350D01*
Y-58404D01*
Y-58458D01*
Y-58512D01*
Y-58566D01*
Y-58620D01*
Y-58674D01*
Y-58728D01*
Y-58782D01*
Y-58836D01*
Y-58890D01*
Y-58944D01*
Y-58998D01*
Y-59052D01*
Y-59106D01*
Y-59161D01*
Y-59215D01*
Y-59269D01*
Y-59323D01*
Y-59377D01*
Y-59431D01*
Y-59485D01*
Y-59539D01*
Y-59593D01*
Y-59647D01*
Y-59701D01*
Y-59755D01*
Y-59809D01*
Y-59863D01*
Y-59917D01*
Y-59971D01*
Y-60026D01*
Y-60080D01*
Y-60134D01*
Y-60188D01*
Y-60242D01*
Y-60296D01*
Y-60350D01*
Y-60404D01*
Y-60458D01*
Y-60512D01*
Y-60566D01*
Y-60620D01*
Y-60674D01*
Y-60728D01*
Y-60782D01*
Y-60836D01*
Y-60891D01*
Y-60945D01*
Y-60999D01*
Y-61053D01*
Y-61107D01*
Y-61161D01*
Y-61215D01*
Y-61269D01*
Y-61323D01*
Y-61377D01*
Y-61431D01*
Y-61485D01*
Y-61539D01*
Y-61593D01*
Y-61647D01*
Y-61702D01*
Y-61756D01*
Y-61810D01*
Y-61864D01*
Y-61918D01*
Y-61972D01*
Y-62026D01*
Y-62080D01*
Y-62134D01*
Y-62188D01*
Y-62242D01*
Y-62296D01*
Y-62350D01*
Y-62404D01*
Y-62458D01*
Y-62512D01*
Y-62566D01*
Y-62621D01*
Y-62675D01*
X372611Y-62727D01*
X372600Y-62778D01*
X372584Y-62828D01*
X372560Y-62875D01*
X372557Y-62880D01*
X372557Y-62882D01*
X372557Y-62889D01*
X372546Y-62941D01*
X372530Y-62990D01*
X372506Y-63037D01*
X372486Y-63068D01*
X372475Y-63098D01*
X372452Y-63145D01*
X372423Y-63189D01*
X372389Y-63228D01*
X372360Y-63254D01*
X372335Y-63282D01*
X372295Y-63317D01*
X372251Y-63346D01*
X372204Y-63369D01*
X372174Y-63380D01*
X372143Y-63400D01*
X372096Y-63423D01*
X372066Y-63434D01*
X372035Y-63454D01*
X371988Y-63477D01*
X371938Y-63494D01*
X371887Y-63504D01*
X371835Y-63508D01*
X366537D01*
X366484Y-63504D01*
X366433Y-63494D01*
X366383Y-63477D01*
X366336Y-63454D01*
X366336Y-63454D01*
X366332Y-63451D01*
X366322Y-63450D01*
X366271Y-63440D01*
X366221Y-63423D01*
X366174Y-63400D01*
X366130Y-63371D01*
X366091Y-63336D01*
X366066Y-63308D01*
X366037Y-63282D01*
X366012Y-63254D01*
X365983Y-63228D01*
X365958Y-63200D01*
X365929Y-63174D01*
X365904Y-63146D01*
X365875Y-63120D01*
X365840Y-63081D01*
X365811Y-63037D01*
X365788Y-62990D01*
X365771Y-62941D01*
X365761Y-62889D01*
X365757Y-62837D01*
Y-62783D01*
Y-62729D01*
Y-62675D01*
Y-62621D01*
Y-62566D01*
Y-62512D01*
Y-62458D01*
Y-62404D01*
Y-62350D01*
Y-62296D01*
Y-62242D01*
Y-62188D01*
Y-62134D01*
Y-62080D01*
Y-62026D01*
Y-61972D01*
Y-61918D01*
Y-61864D01*
Y-61810D01*
Y-61756D01*
Y-61702D01*
Y-61647D01*
Y-61593D01*
Y-61539D01*
Y-61485D01*
Y-61431D01*
Y-61377D01*
Y-61323D01*
Y-61269D01*
Y-61215D01*
Y-61161D01*
Y-61107D01*
Y-61053D01*
Y-60999D01*
Y-60945D01*
Y-60891D01*
Y-60836D01*
Y-60782D01*
Y-60728D01*
Y-60674D01*
Y-60620D01*
Y-60566D01*
Y-60512D01*
Y-60458D01*
Y-60404D01*
Y-60350D01*
Y-60296D01*
Y-60242D01*
Y-60188D01*
Y-60134D01*
Y-60080D01*
Y-60026D01*
Y-59971D01*
Y-59917D01*
Y-59863D01*
Y-59809D01*
Y-59755D01*
Y-59740D01*
X365757Y-59739D01*
X365734Y-59692D01*
X365717Y-59643D01*
X365707Y-59591D01*
X365704Y-59542D01*
X365687Y-59523D01*
X365663Y-59502D01*
X365657Y-59501D01*
X365645Y-59498D01*
X365616Y-59504D01*
X365607Y-59504D01*
X365602Y-59508D01*
X365591Y-59513D01*
X365586Y-59523D01*
X365583Y-59528D01*
X365583Y-59537D01*
X365572Y-59589D01*
X365556Y-59638D01*
X365532Y-59685D01*
X365532Y-59686D01*
Y-59701D01*
Y-59755D01*
Y-59809D01*
Y-59863D01*
Y-59917D01*
Y-59971D01*
Y-60026D01*
Y-60080D01*
Y-60134D01*
Y-60188D01*
Y-60242D01*
Y-60296D01*
Y-60350D01*
Y-60404D01*
Y-60458D01*
Y-60512D01*
Y-60566D01*
Y-60620D01*
Y-60674D01*
Y-60728D01*
Y-60782D01*
Y-60836D01*
Y-60891D01*
Y-60945D01*
Y-60999D01*
Y-61053D01*
Y-61107D01*
Y-61161D01*
Y-61215D01*
Y-61269D01*
Y-61323D01*
Y-61377D01*
Y-61431D01*
Y-61485D01*
Y-61539D01*
Y-61593D01*
Y-61647D01*
Y-61702D01*
Y-61756D01*
Y-61810D01*
Y-61864D01*
Y-61918D01*
Y-61972D01*
Y-62026D01*
Y-62080D01*
Y-62134D01*
Y-62188D01*
Y-62242D01*
Y-62296D01*
Y-62350D01*
Y-62404D01*
Y-62458D01*
Y-62512D01*
Y-62566D01*
Y-62621D01*
Y-62675D01*
Y-62729D01*
Y-62783D01*
X365528Y-62835D01*
X365518Y-62887D01*
X365501Y-62936D01*
X365478Y-62983D01*
X365458Y-63014D01*
X365447Y-63044D01*
X365424Y-63091D01*
X365395Y-63135D01*
X365360Y-63174D01*
X365332Y-63200D01*
X365306Y-63228D01*
X365278Y-63254D01*
X365252Y-63282D01*
X365224Y-63308D01*
X365198Y-63336D01*
X365159Y-63371D01*
X365115Y-63400D01*
X365068Y-63423D01*
X365019Y-63440D01*
X364967Y-63450D01*
X364958Y-63451D01*
X364953Y-63454D01*
X364906Y-63477D01*
X364856Y-63494D01*
X364805Y-63504D01*
X364753Y-63508D01*
X354427D01*
X354375Y-63504D01*
X354323Y-63494D01*
X354273Y-63477D01*
X354226Y-63454D01*
X354196Y-63434D01*
X354165Y-63423D01*
X354118Y-63400D01*
X354087Y-63380D01*
X354057Y-63369D01*
X354010Y-63346D01*
X353966Y-63317D01*
X353927Y-63282D01*
X353902Y-63254D01*
X353873Y-63228D01*
X353838Y-63189D01*
X353809Y-63145D01*
X353786Y-63098D01*
X353776Y-63068D01*
X353755Y-63037D01*
X353732Y-62990D01*
X353722Y-62960D01*
X353701Y-62929D01*
X353678Y-62882D01*
X353661Y-62832D01*
X353651Y-62781D01*
X353647Y-62729D01*
Y-62675D01*
Y-62621D01*
Y-62566D01*
Y-62512D01*
Y-62458D01*
Y-62404D01*
Y-62350D01*
Y-62296D01*
Y-62242D01*
Y-62188D01*
Y-62134D01*
Y-62080D01*
Y-62026D01*
Y-61972D01*
Y-61918D01*
Y-61864D01*
Y-61810D01*
Y-61756D01*
Y-61702D01*
Y-61647D01*
Y-61593D01*
Y-61539D01*
Y-61485D01*
Y-61431D01*
Y-61377D01*
Y-61323D01*
Y-61269D01*
Y-61215D01*
Y-61161D01*
Y-61107D01*
Y-61053D01*
Y-60999D01*
Y-60945D01*
Y-60891D01*
Y-60836D01*
Y-60782D01*
Y-60728D01*
Y-60674D01*
Y-60620D01*
Y-60566D01*
Y-60512D01*
Y-60458D01*
Y-60404D01*
Y-60350D01*
Y-60296D01*
Y-60242D01*
Y-60188D01*
Y-60134D01*
Y-60080D01*
Y-60026D01*
Y-59971D01*
Y-59917D01*
Y-59863D01*
Y-59809D01*
Y-59755D01*
Y-59701D01*
Y-59647D01*
Y-59593D01*
Y-59539D01*
Y-59485D01*
Y-59431D01*
Y-59377D01*
Y-59323D01*
Y-59269D01*
Y-59215D01*
Y-59161D01*
Y-59106D01*
Y-59052D01*
Y-58998D01*
Y-58944D01*
Y-58890D01*
Y-58836D01*
Y-58782D01*
Y-58728D01*
Y-58674D01*
Y-58620D01*
Y-58566D01*
Y-58512D01*
Y-58458D01*
Y-58404D01*
Y-58350D01*
Y-58296D01*
Y-58241D01*
Y-58187D01*
Y-58133D01*
Y-58079D01*
Y-58025D01*
Y-57971D01*
Y-57917D01*
Y-57863D01*
Y-57809D01*
Y-57755D01*
Y-57701D01*
Y-57647D01*
Y-57593D01*
Y-57577D01*
X353647Y-57577D01*
X353624Y-57530D01*
X353618Y-57512D01*
X353617Y-57511D01*
X353603Y-57498D01*
X353590Y-57483D01*
X353571Y-57477D01*
X353524Y-57453D01*
X353523Y-57453D01*
X314799D01*
X314747Y-57450D01*
X314696Y-57439D01*
X314646Y-57423D01*
X314599Y-57399D01*
X314598Y-57399D01*
X314583D01*
X314531Y-57395D01*
X314479Y-57385D01*
X314430Y-57368D01*
X314383Y-57345D01*
X314378Y-57342D01*
X314369Y-57341D01*
X314317Y-57331D01*
X314267Y-57314D01*
X314220Y-57291D01*
X314190Y-57271D01*
X314159Y-57260D01*
X314112Y-57237D01*
X314082Y-57217D01*
X314051Y-57206D01*
X314004Y-57183D01*
X313973Y-57162D01*
X313943Y-57152D01*
X313896Y-57129D01*
X313886Y-57122D01*
X313865Y-57108D01*
X313835Y-57098D01*
X313788Y-57075D01*
X313744Y-57046D01*
X313705Y-57011D01*
X313692Y-56997D01*
X313673Y-56990D01*
X313626Y-56967D01*
X313582Y-56938D01*
X313543Y-56903D01*
X313517Y-56874D01*
X313489Y-56849D01*
X313476Y-56834D01*
X313457Y-56828D01*
X313409Y-56805D01*
X313366Y-56775D01*
X313327Y-56741D01*
X313301Y-56712D01*
X313298Y-56709D01*
X313273Y-56687D01*
X313247Y-56658D01*
X313218Y-56633D01*
X313193Y-56604D01*
X313164Y-56579D01*
X313139Y-56550D01*
X313110Y-56525D01*
X313085Y-56496D01*
X313056Y-56471D01*
X313031Y-56442D01*
X313002Y-56416D01*
X312977Y-56388D01*
X312948Y-56362D01*
X312923Y-56334D01*
X312894Y-56308D01*
X312869Y-56280D01*
X312840Y-56254D01*
X312815Y-56226D01*
X312786Y-56200D01*
X312751Y-56161D01*
X312722Y-56117D01*
X312699Y-56070D01*
X312692Y-56051D01*
X312678Y-56038D01*
X312653Y-56009D01*
X312624Y-55984D01*
X312589Y-55945D01*
X312560Y-55901D01*
X312537Y-55854D01*
X312530Y-55835D01*
X312516Y-55822D01*
X312481Y-55782D01*
X312452Y-55739D01*
X312429Y-55692D01*
X312422Y-55673D01*
X312407Y-55660D01*
X312373Y-55620D01*
X312344Y-55577D01*
X312321Y-55530D01*
X312310Y-55499D01*
X312290Y-55468D01*
X312266Y-55422D01*
X312256Y-55391D01*
X312236Y-55360D01*
X312212Y-55313D01*
X312202Y-55283D01*
X312182Y-55252D01*
X312158Y-55205D01*
X312141Y-55156D01*
X312131Y-55104D01*
X312131Y-55095D01*
X312127Y-55090D01*
X312104Y-55043D01*
X312087Y-54993D01*
X312077Y-54942D01*
X312077Y-54933D01*
X312073Y-54928D01*
X312050Y-54881D01*
X312033Y-54831D01*
X312023Y-54780D01*
X312023Y-54770D01*
X312019Y-54766D01*
X311996Y-54719D01*
X311979Y-54669D01*
X311969Y-54618D01*
X311968Y-54608D01*
X311965Y-54603D01*
X311942Y-54557D01*
X311925Y-54507D01*
X311915Y-54455D01*
X311912Y-54403D01*
Y-54349D01*
Y-54334D01*
X311911Y-54333D01*
X311888Y-54286D01*
X311871Y-54237D01*
X311861Y-54185D01*
X311858Y-54133D01*
Y-54079D01*
Y-54025D01*
Y-53971D01*
Y-53917D01*
Y-53863D01*
Y-53808D01*
Y-53793D01*
X311857Y-53793D01*
X311834Y-53746D01*
X311817Y-53696D01*
X311807Y-53645D01*
X311804Y-53592D01*
Y-53538D01*
Y-53484D01*
X311807Y-53432D01*
X311817Y-53380D01*
X311834Y-53331D01*
X311857Y-53284D01*
X311858Y-53283D01*
Y-53268D01*
Y-53214D01*
Y-53160D01*
Y-53106D01*
Y-53052D01*
Y-52997D01*
X311861Y-52945D01*
X311871Y-52894D01*
X311888Y-52844D01*
X311911Y-52797D01*
X311912Y-52797D01*
Y-52781D01*
Y-52727D01*
Y-52673D01*
X311915Y-52621D01*
X311925Y-52569D01*
X311942Y-52520D01*
X311965Y-52473D01*
X311968Y-52468D01*
X311969Y-52459D01*
X311979Y-52407D01*
X311996Y-52358D01*
X312019Y-52311D01*
X312023Y-52306D01*
X312023Y-52296D01*
X312033Y-52245D01*
X312050Y-52195D01*
X312073Y-52148D01*
X312077Y-52144D01*
X312077Y-52134D01*
X312087Y-52083D01*
X312104Y-52033D01*
X312127Y-51986D01*
X312148Y-51955D01*
X312158Y-51925D01*
X312182Y-51878D01*
X312202Y-51847D01*
X312205Y-51839D01*
X312212Y-51817D01*
X312236Y-51770D01*
X312256Y-51739D01*
X312266Y-51709D01*
X312290Y-51662D01*
X312310Y-51631D01*
X312321Y-51601D01*
X312344Y-51554D01*
X312373Y-51510D01*
X312407Y-51471D01*
X312422Y-51458D01*
X312429Y-51438D01*
X312452Y-51391D01*
X312481Y-51348D01*
X312516Y-51308D01*
X312530Y-51296D01*
X312537Y-51276D01*
X312560Y-51229D01*
X312589Y-51186D01*
X312624Y-51146D01*
X312653Y-51121D01*
X312678Y-51092D01*
X312707Y-51067D01*
X312732Y-51038D01*
X312747Y-51025D01*
X312753Y-51006D01*
X312776Y-50959D01*
X312805Y-50915D01*
X312840Y-50876D01*
X312869Y-50851D01*
X312894Y-50822D01*
X312923Y-50797D01*
X312948Y-50768D01*
X312977Y-50743D01*
X313002Y-50714D01*
X313031Y-50688D01*
X313056Y-50660D01*
X313085Y-50634D01*
X313110Y-50606D01*
X313150Y-50571D01*
X313193Y-50542D01*
X313240Y-50519D01*
X313260Y-50512D01*
X313273Y-50498D01*
X313301Y-50472D01*
X313327Y-50443D01*
X313355Y-50418D01*
X313381Y-50389D01*
X313420Y-50355D01*
X313464Y-50326D01*
X313511Y-50302D01*
X313530Y-50296D01*
X313543Y-50281D01*
X313582Y-50247D01*
X313626Y-50217D01*
X313673Y-50194D01*
X313703Y-50184D01*
X313734Y-50164D01*
X313781Y-50140D01*
X313800Y-50134D01*
X313802Y-50132D01*
X313813Y-50119D01*
X313853Y-50085D01*
X313896Y-50055D01*
X313943Y-50032D01*
X313973Y-50022D01*
X314004Y-50001D01*
X314051Y-49978D01*
X314082Y-49968D01*
X314112Y-49947D01*
X314159Y-49924D01*
X314209Y-49907D01*
X314261Y-49897D01*
X314270Y-49896D01*
X314275Y-49893D01*
X314322Y-49870D01*
X314371Y-49853D01*
X314423Y-49843D01*
X314432Y-49842D01*
X314437Y-49839D01*
X314484Y-49816D01*
X314533Y-49799D01*
X314585Y-49789D01*
X314594Y-49788D01*
X314599Y-49785D01*
X314646Y-49762D01*
X314696Y-49745D01*
X314747Y-49735D01*
X314756Y-49734D01*
X314761Y-49731D01*
X314808Y-49708D01*
X314858Y-49691D01*
X314909Y-49681D01*
X314962Y-49677D01*
X315031D01*
X315031Y-49677D01*
X315078Y-49654D01*
X315128Y-49637D01*
X315179Y-49627D01*
X315232Y-49623D01*
X326222D01*
X326222Y-49623D01*
X326269Y-49600D01*
X326319Y-49583D01*
X326370Y-49573D01*
X326423Y-49569D01*
X326708D01*
X326709Y-49569D01*
X326756Y-49546D01*
X326805Y-49529D01*
X326857Y-49518D01*
X326909Y-49515D01*
X326979D01*
X326979Y-49515D01*
X327026Y-49492D01*
X327076Y-49475D01*
X327127Y-49464D01*
X327180Y-49461D01*
X327195D01*
X327195Y-49461D01*
X327242Y-49437D01*
X327273Y-49427D01*
X327304Y-49407D01*
X327350Y-49383D01*
X327400Y-49367D01*
X327452Y-49356D01*
X327461Y-49356D01*
X327466Y-49352D01*
X327513Y-49329D01*
X327543Y-49319D01*
X327574Y-49299D01*
X327621Y-49275D01*
X327651Y-49265D01*
X327682Y-49244D01*
X327729Y-49221D01*
X327759Y-49211D01*
X327790Y-49190D01*
X327837Y-49167D01*
X327867Y-49157D01*
X327898Y-49136D01*
X327945Y-49113D01*
X327964Y-49107D01*
X327977Y-49092D01*
X328017Y-49057D01*
X328060Y-49028D01*
X328107Y-49005D01*
X328127Y-48998D01*
X328139Y-48984D01*
X328168Y-48959D01*
X328194Y-48930D01*
X328233Y-48895D01*
X328277Y-48866D01*
X328324Y-48843D01*
X328343Y-48836D01*
X328356Y-48822D01*
X328385Y-48796D01*
X328410Y-48768D01*
X328413Y-48765D01*
X328439Y-48742D01*
X328464Y-48713D01*
X328493Y-48688D01*
X328518Y-48659D01*
X328547Y-48634D01*
X328572Y-48605D01*
X328601Y-48580D01*
X328626Y-48551D01*
X328655Y-48526D01*
X328680Y-48497D01*
X328695Y-48484D01*
X328701Y-48465D01*
X328725Y-48418D01*
X328754Y-48374D01*
X328788Y-48335D01*
X328817Y-48310D01*
X328842Y-48281D01*
X328857Y-48268D01*
X328864Y-48249D01*
X328887Y-48202D01*
X328916Y-48158D01*
X328951Y-48119D01*
X328965Y-48106D01*
X328972Y-48087D01*
X328995Y-48040D01*
X329015Y-48009D01*
X329026Y-47978D01*
X329049Y-47932D01*
X329069Y-47901D01*
X329080Y-47870D01*
X329103Y-47823D01*
X329119Y-47799D01*
X329124Y-47793D01*
X329134Y-47762D01*
X329157Y-47715D01*
X329178Y-47684D01*
X329188Y-47654D01*
X329211Y-47607D01*
X329214Y-47602D01*
X329215Y-47593D01*
X329225Y-47542D01*
X329242Y-47492D01*
X329265Y-47445D01*
X329268Y-47440D01*
X329269Y-47431D01*
X329279Y-47379D01*
X329296Y-47330D01*
X329319Y-47283D01*
X329322Y-47278D01*
X329323Y-47269D01*
X329333Y-47217D01*
X329350Y-47168D01*
X329373Y-47120D01*
X329374Y-47120D01*
Y-47105D01*
Y-47051D01*
X329377Y-46998D01*
X329387Y-46947D01*
X329404Y-46897D01*
X329427Y-46850D01*
X329428Y-46850D01*
Y-46834D01*
Y-46780D01*
Y-46726D01*
Y-46672D01*
Y-46618D01*
Y-46564D01*
Y-46510D01*
Y-46456D01*
Y-46402D01*
Y-46348D01*
Y-46294D01*
Y-46240D01*
Y-46186D01*
Y-46132D01*
Y-46116D01*
X329427Y-46116D01*
X329404Y-46069D01*
X329387Y-46019D01*
X329377Y-45968D01*
X329374Y-45915D01*
Y-45861D01*
Y-45846D01*
X329373Y-45845D01*
X329350Y-45798D01*
X329333Y-45749D01*
X329323Y-45697D01*
X329322Y-45688D01*
X329319Y-45683D01*
X329296Y-45636D01*
X329279Y-45587D01*
X329269Y-45535D01*
X329268Y-45526D01*
X329265Y-45521D01*
X329242Y-45474D01*
X329225Y-45424D01*
X329215Y-45373D01*
X329214Y-45364D01*
X329211Y-45359D01*
X329188Y-45312D01*
X329178Y-45282D01*
X329157Y-45251D01*
X329134Y-45204D01*
X329124Y-45173D01*
X329103Y-45143D01*
X329080Y-45096D01*
X329078Y-45091D01*
X329069Y-45065D01*
X329049Y-45035D01*
X329026Y-44987D01*
X329019Y-44968D01*
X329005Y-44955D01*
X328970Y-44916D01*
X328941Y-44872D01*
X328918Y-44825D01*
X328911Y-44806D01*
X328896Y-44793D01*
X328862Y-44754D01*
X328833Y-44710D01*
X328809Y-44663D01*
X328805Y-44649D01*
X328803Y-44644D01*
X328788Y-44631D01*
X328763Y-44602D01*
X328734Y-44577D01*
X328709Y-44548D01*
X328680Y-44523D01*
X328646Y-44484D01*
X328616Y-44440D01*
X328593Y-44393D01*
X328587Y-44375D01*
X328587Y-44374D01*
X328572Y-44361D01*
X328547Y-44332D01*
X328518Y-44307D01*
X328493Y-44278D01*
X328464Y-44253D01*
X328451Y-44238D01*
X328432Y-44231D01*
X328385Y-44208D01*
X328341Y-44179D01*
X328302Y-44144D01*
X328276Y-44116D01*
X328248Y-44090D01*
X328222Y-44062D01*
X328194Y-44036D01*
X328181Y-44022D01*
X328162Y-44015D01*
X328114Y-43992D01*
X328071Y-43963D01*
X328031Y-43928D01*
X328018Y-43913D01*
X327999Y-43907D01*
X327952Y-43884D01*
X327921Y-43863D01*
X327891Y-43853D01*
X327844Y-43830D01*
X327800Y-43801D01*
X327761Y-43766D01*
X327748Y-43751D01*
X327729Y-43745D01*
X327682Y-43722D01*
X327651Y-43701D01*
X327621Y-43691D01*
X327574Y-43668D01*
X327573Y-43667D01*
X327569Y-43664D01*
X327560Y-43664D01*
X327508Y-43654D01*
X327459Y-43637D01*
X327412Y-43613D01*
X327381Y-43593D01*
X327350Y-43583D01*
X327304Y-43559D01*
X327299Y-43556D01*
X327289Y-43556D01*
X327238Y-43545D01*
X327188Y-43529D01*
X327141Y-43505D01*
X327141Y-43505D01*
X327126D01*
X327073Y-43502D01*
X327022Y-43491D01*
X326972Y-43475D01*
X326925Y-43451D01*
X326924Y-43451D01*
X326855D01*
X326803Y-43448D01*
X326751Y-43437D01*
X326702Y-43420D01*
X326655Y-43397D01*
X326654Y-43397D01*
X326315D01*
X326288Y-43395D01*
X326260Y-43397D01*
X310042D01*
X310015Y-43395D01*
X309988Y-43397D01*
X309880D01*
X309827Y-43393D01*
X309776Y-43383D01*
X309726Y-43366D01*
X309679Y-43343D01*
X309679Y-43343D01*
X309501D01*
X309449Y-43339D01*
X309398Y-43329D01*
X309348Y-43312D01*
X309301Y-43289D01*
X309300Y-43289D01*
X309231D01*
X309179Y-43285D01*
X309127Y-43275D01*
X309078Y-43258D01*
X309031Y-43235D01*
X309030Y-43235D01*
X309026Y-43232D01*
X309016Y-43231D01*
X308965Y-43221D01*
X308915Y-43204D01*
X308868Y-43181D01*
X308864Y-43178D01*
X308854Y-43177D01*
X308803Y-43167D01*
X308753Y-43150D01*
X308706Y-43127D01*
X308701Y-43124D01*
X308692Y-43123D01*
X308641Y-43113D01*
X308591Y-43096D01*
X308544Y-43073D01*
X308513Y-43052D01*
X308483Y-43042D01*
X308436Y-43019D01*
X308405Y-42998D01*
X308375Y-42988D01*
X308328Y-42965D01*
X308297Y-42944D01*
X308267Y-42934D01*
X308220Y-42911D01*
X308189Y-42890D01*
X308158Y-42880D01*
X308112Y-42857D01*
X308068Y-42827D01*
X308029Y-42793D01*
X308016Y-42778D01*
X307996Y-42772D01*
X307949Y-42748D01*
X307906Y-42719D01*
X307866Y-42685D01*
X307853Y-42670D01*
X307834Y-42663D01*
X307787Y-42640D01*
X307744Y-42611D01*
X307704Y-42577D01*
X307679Y-42548D01*
X307650Y-42523D01*
X307637Y-42508D01*
X307618Y-42501D01*
X307571Y-42478D01*
X307527Y-42449D01*
X307488Y-42415D01*
X307463Y-42386D01*
X307434Y-42360D01*
X307408Y-42332D01*
X307380Y-42306D01*
X307354Y-42278D01*
X307326Y-42252D01*
X307300Y-42224D01*
X307297Y-42220D01*
X307272Y-42198D01*
X307246Y-42169D01*
X307218Y-42144D01*
X307192Y-42115D01*
X307164Y-42090D01*
X307138Y-42061D01*
X307109Y-42036D01*
X307075Y-41997D01*
X307046Y-41953D01*
X307023Y-41906D01*
X307016Y-41887D01*
X307001Y-41874D01*
X306982Y-41852D01*
X306976Y-41845D01*
X306947Y-41820D01*
X306922Y-41791D01*
X306893Y-41766D01*
X306859Y-41726D01*
X306829Y-41683D01*
X306806Y-41636D01*
X306800Y-41617D01*
X306800Y-41616D01*
X306785Y-41603D01*
X306750Y-41564D01*
X306721Y-41521D01*
X306698Y-41473D01*
X306688Y-41443D01*
X306667Y-41412D01*
X306644Y-41365D01*
X306634Y-41335D01*
X306613Y-41304D01*
X306590Y-41257D01*
X306585Y-41243D01*
X306580Y-41227D01*
X306559Y-41196D01*
X306536Y-41149D01*
X306530Y-41132D01*
X306526Y-41119D01*
X306505Y-41088D01*
X306482Y-41041D01*
X306472Y-41011D01*
X306451Y-40980D01*
X306428Y-40933D01*
X306411Y-40883D01*
X306401Y-40832D01*
X306400Y-40822D01*
X306397Y-40818D01*
X306374Y-40771D01*
X306357Y-40721D01*
X306347Y-40670D01*
X306346Y-40660D01*
X306343Y-40655D01*
X306320Y-40609D01*
X306303Y-40559D01*
X306293Y-40507D01*
X306292Y-40498D01*
X306289Y-40493D01*
X306266Y-40446D01*
X306249Y-40397D01*
X306239Y-40345D01*
X306235Y-40293D01*
Y-40239D01*
Y-40224D01*
X306235Y-40223D01*
X306212Y-40176D01*
X306195Y-40126D01*
X306185Y-40075D01*
X306181Y-40023D01*
Y-39968D01*
Y-39915D01*
Y-39860D01*
Y-39806D01*
Y-39752D01*
Y-39698D01*
Y-39644D01*
Y-39590D01*
Y-39536D01*
Y-39482D01*
Y-39428D01*
Y-39374D01*
Y-39320D01*
Y-39266D01*
Y-39212D01*
Y-39158D01*
Y-39103D01*
Y-39050D01*
Y-38995D01*
Y-38941D01*
Y-38887D01*
X306185Y-38835D01*
X306195Y-38783D01*
X306212Y-38734D01*
X306235Y-38687D01*
X306235Y-38686D01*
Y-38671D01*
Y-38617D01*
X306239Y-38565D01*
X306249Y-38513D01*
X306266Y-38464D01*
X306289Y-38417D01*
X306289Y-38416D01*
Y-38401D01*
X306293Y-38348D01*
X306303Y-38297D01*
X306320Y-38247D01*
X306343Y-38200D01*
X306346Y-38196D01*
X306347Y-38186D01*
X306357Y-38135D01*
X306374Y-38085D01*
X306397Y-38038D01*
X306413Y-38014D01*
X306417Y-38007D01*
X306418Y-38006D01*
X306428Y-37977D01*
X306451Y-37930D01*
X306454Y-37925D01*
X306455Y-37916D01*
X306465Y-37865D01*
X306482Y-37815D01*
X306505Y-37768D01*
X306526Y-37737D01*
X306527Y-37733D01*
X306536Y-37707D01*
X306559Y-37660D01*
X306571Y-37642D01*
X306580Y-37629D01*
X306590Y-37599D01*
X306613Y-37552D01*
X306642Y-37508D01*
X306677Y-37468D01*
X306692Y-37456D01*
X306698Y-37436D01*
X306721Y-37389D01*
X306742Y-37359D01*
X306752Y-37328D01*
X306775Y-37281D01*
X306804Y-37238D01*
X306839Y-37198D01*
X306868Y-37173D01*
X306893Y-37144D01*
X306908Y-37131D01*
X306914Y-37112D01*
X306938Y-37065D01*
X306967Y-37021D01*
X307001Y-36982D01*
X307004Y-36979D01*
X307030Y-36957D01*
X307055Y-36928D01*
X307084Y-36903D01*
X307109Y-36874D01*
X307138Y-36849D01*
X307164Y-36820D01*
X307192Y-36794D01*
X307218Y-36766D01*
X307246Y-36740D01*
X307272Y-36712D01*
X307275Y-36709D01*
X307300Y-36686D01*
X307326Y-36658D01*
X307329Y-36655D01*
X307354Y-36632D01*
X307380Y-36604D01*
X307408Y-36578D01*
X307434Y-36549D01*
X307463Y-36524D01*
X307488Y-36495D01*
X307517Y-36470D01*
X307542Y-36441D01*
X307571Y-36416D01*
X307596Y-36387D01*
X307635Y-36353D01*
X307679Y-36324D01*
X307726Y-36300D01*
X307737Y-36297D01*
X307745Y-36294D01*
X307758Y-36279D01*
X307787Y-36254D01*
X307812Y-36225D01*
X307852Y-36191D01*
X307895Y-36161D01*
X307942Y-36138D01*
X307953Y-36134D01*
X307962Y-36132D01*
X307974Y-36117D01*
X308014Y-36082D01*
X308057Y-36053D01*
X308104Y-36030D01*
X308135Y-36020D01*
X308166Y-35999D01*
X308213Y-35976D01*
X308243Y-35966D01*
X308274Y-35945D01*
X308321Y-35922D01*
X308351Y-35912D01*
X308382Y-35891D01*
X308429Y-35868D01*
X308459Y-35858D01*
X308490Y-35837D01*
X308537Y-35814D01*
X308587Y-35797D01*
X308638Y-35787D01*
X308647Y-35786D01*
X308652Y-35783D01*
X308699Y-35760D01*
X308749Y-35743D01*
X308800Y-35733D01*
X308809Y-35732D01*
X308814Y-35729D01*
X308861Y-35706D01*
X308911Y-35689D01*
X308962Y-35679D01*
X308972Y-35678D01*
X308977Y-35675D01*
X309023Y-35652D01*
X309073Y-35635D01*
X309125Y-35625D01*
X309177Y-35621D01*
X309192D01*
X309193Y-35621D01*
X309240Y-35598D01*
X309289Y-35581D01*
X309341Y-35570D01*
X309393Y-35567D01*
X309462D01*
X309463Y-35567D01*
X309510Y-35544D01*
X309560Y-35527D01*
X309611Y-35516D01*
X309664Y-35513D01*
X319842D01*
X319843Y-35513D01*
X319890Y-35489D01*
X319940Y-35473D01*
X319991Y-35462D01*
X320043Y-35459D01*
X320221D01*
X320221Y-35459D01*
X320268Y-35435D01*
X320318Y-35419D01*
X320370Y-35408D01*
X320422Y-35405D01*
X320437D01*
X320438Y-35405D01*
X320485Y-35381D01*
X320534Y-35364D01*
X320586Y-35354D01*
X320595Y-35354D01*
X320600Y-35350D01*
X320647Y-35327D01*
X320696Y-35310D01*
X320748Y-35300D01*
X320757Y-35300D01*
X320762Y-35296D01*
X320809Y-35273D01*
X320839Y-35263D01*
X320870Y-35242D01*
X320917Y-35219D01*
X320967Y-35202D01*
X321018Y-35192D01*
X321028Y-35192D01*
X321032Y-35188D01*
X321079Y-35165D01*
X321099Y-35159D01*
X321111Y-35144D01*
X321151Y-35109D01*
X321195Y-35080D01*
X321241Y-35057D01*
X321272Y-35047D01*
X321303Y-35026D01*
X321350Y-35003D01*
X321369Y-34996D01*
X321376Y-34988D01*
X321382Y-34982D01*
X321421Y-34947D01*
X321465Y-34918D01*
X321512Y-34895D01*
X321531Y-34888D01*
X321544Y-34874D01*
X321573Y-34848D01*
X321598Y-34819D01*
X321637Y-34785D01*
X321681Y-34756D01*
X321728Y-34733D01*
X321747Y-34726D01*
X321760Y-34711D01*
X321771Y-34702D01*
X321789Y-34686D01*
X321814Y-34657D01*
X321843Y-34632D01*
X321868Y-34603D01*
X321897Y-34578D01*
X321922Y-34549D01*
X321951Y-34524D01*
X321976Y-34495D01*
X322005Y-34470D01*
X322030Y-34441D01*
X322051Y-34423D01*
X322059Y-34416D01*
X322085Y-34387D01*
X322088Y-34385D01*
X322099Y-34374D01*
X322106Y-34355D01*
X322129Y-34308D01*
X322158Y-34264D01*
X322193Y-34225D01*
X322221Y-34200D01*
X322247Y-34171D01*
X322262Y-34158D01*
X322268Y-34139D01*
X322291Y-34092D01*
X322320Y-34048D01*
X322355Y-34009D01*
X322370Y-33996D01*
X322370Y-33996D01*
X322376Y-33976D01*
X322399Y-33929D01*
X322420Y-33899D01*
X322430Y-33868D01*
X322453Y-33821D01*
X322474Y-33790D01*
X322484Y-33760D01*
X322507Y-33713D01*
X322528Y-33682D01*
X322538Y-33652D01*
X322562Y-33605D01*
X322582Y-33574D01*
X322592Y-33544D01*
X322616Y-33497D01*
X322619Y-33492D01*
X322619Y-33483D01*
X322630Y-33431D01*
X322646Y-33382D01*
X322670Y-33335D01*
X322673Y-33330D01*
X322673Y-33321D01*
X322684Y-33269D01*
X322701Y-33220D01*
X322724Y-33173D01*
X322724Y-33172D01*
Y-33157D01*
X322727Y-33104D01*
X322738Y-33053D01*
X322755Y-33003D01*
X322778Y-32956D01*
X322778Y-32956D01*
Y-32941D01*
Y-32886D01*
Y-32832D01*
X322781Y-32780D01*
X322792Y-32729D01*
X322809Y-32679D01*
X322832Y-32632D01*
X322832Y-32631D01*
Y-32616D01*
Y-32562D01*
Y-32508D01*
Y-32454D01*
Y-32400D01*
Y-32346D01*
Y-32292D01*
Y-32238D01*
Y-32184D01*
D01*
Y-32168D01*
X322832Y-32168D01*
X322809Y-32121D01*
X322792Y-32071D01*
X322781Y-32020D01*
X322778Y-31967D01*
Y-31913D01*
Y-31859D01*
Y-31844D01*
X322778Y-31843D01*
X322755Y-31796D01*
X322738Y-31747D01*
X322727Y-31695D01*
X322724Y-31643D01*
Y-31628D01*
X322724Y-31627D01*
X322701Y-31580D01*
X322684Y-31530D01*
X322673Y-31479D01*
X322673Y-31470D01*
X322670Y-31465D01*
X322646Y-31418D01*
X322630Y-31368D01*
X322619Y-31317D01*
X322619Y-31308D01*
X322616Y-31303D01*
X322592Y-31256D01*
X322582Y-31225D01*
X322562Y-31195D01*
X322538Y-31148D01*
X322528Y-31117D01*
X322507Y-31087D01*
X322484Y-31040D01*
X322474Y-31009D01*
X322453Y-30978D01*
X322430Y-30931D01*
X322420Y-30901D01*
X322399Y-30870D01*
X322376Y-30823D01*
X322370Y-30804D01*
X322355Y-30791D01*
X322320Y-30752D01*
X322291Y-30708D01*
X322268Y-30661D01*
X322262Y-30642D01*
X322247Y-30629D01*
X322212Y-30590D01*
X322183Y-30546D01*
X322160Y-30499D01*
X322158Y-30492D01*
X322153Y-30480D01*
X322139Y-30467D01*
X322113Y-30438D01*
X322085Y-30413D01*
X322059Y-30384D01*
X322030Y-30359D01*
X322005Y-30330D01*
X321976Y-30305D01*
X321951Y-30276D01*
X321922Y-30250D01*
X321897Y-30222D01*
X321868Y-30196D01*
X321843Y-30168D01*
X321814Y-30142D01*
X321789Y-30114D01*
X321760Y-30088D01*
X321735Y-30059D01*
X321706Y-30034D01*
X321693Y-30020D01*
X321674Y-30013D01*
X321627Y-29990D01*
X321583Y-29961D01*
X321544Y-29926D01*
X321519Y-29897D01*
X321490Y-29872D01*
X321486Y-29868D01*
X321477Y-29857D01*
X321458Y-29851D01*
X321411Y-29828D01*
X321367Y-29798D01*
X321328Y-29764D01*
X321315Y-29749D01*
X321296Y-29743D01*
X321249Y-29719D01*
X321218Y-29699D01*
X321187Y-29689D01*
X321140Y-29665D01*
X321110Y-29645D01*
X321079Y-29635D01*
X321032Y-29611D01*
X321002Y-29591D01*
X320971Y-29581D01*
X320924Y-29557D01*
X320919Y-29554D01*
X320910Y-29554D01*
X320859Y-29543D01*
X320809Y-29526D01*
X320762Y-29503D01*
X320752Y-29496D01*
X320731Y-29483D01*
X320701Y-29472D01*
X320654Y-29449D01*
X320653Y-29449D01*
X320638D01*
X320586Y-29445D01*
X320534Y-29435D01*
X320485Y-29418D01*
X320438Y-29395D01*
X320437Y-29395D01*
X320422D01*
X320370Y-29391D01*
X320318Y-29381D01*
X320268Y-29364D01*
X320221Y-29341D01*
X320221Y-29341D01*
X320097D01*
X320045Y-29337D01*
X319994Y-29327D01*
X319944Y-29310D01*
X319897Y-29287D01*
X319897Y-29287D01*
X292039D01*
X291987Y-29283D01*
X291935Y-29273D01*
X291886Y-29256D01*
X291839Y-29233D01*
X291838Y-29233D01*
X291715D01*
X291663Y-29229D01*
X291611Y-29219D01*
X291562Y-29202D01*
X291514Y-29179D01*
X291514Y-29179D01*
X291499D01*
X291446Y-29175D01*
X291395Y-29165D01*
X291345Y-29148D01*
X291298Y-29125D01*
X291293Y-29122D01*
X291284Y-29121D01*
X291233Y-29111D01*
X291183Y-29094D01*
X291136Y-29071D01*
X291131Y-29068D01*
X291122Y-29067D01*
X291071Y-29057D01*
X291021Y-29040D01*
X290974Y-29017D01*
X290943Y-28996D01*
X290913Y-28986D01*
X290866Y-28963D01*
X290835Y-28942D01*
X290805Y-28932D01*
X290758Y-28909D01*
X290757Y-28908D01*
X290753Y-28905D01*
X290743Y-28905D01*
X290692Y-28895D01*
X290642Y-28878D01*
X290595Y-28855D01*
X290552Y-28825D01*
X290512Y-28791D01*
X290502Y-28779D01*
X290499Y-28776D01*
X290480Y-28770D01*
X290433Y-28746D01*
X290411Y-28732D01*
X290402Y-28726D01*
X290372Y-28716D01*
X290325Y-28692D01*
X290282Y-28663D01*
X290242Y-28629D01*
X290229Y-28614D01*
X290210Y-28607D01*
X290163Y-28584D01*
X290119Y-28555D01*
X290080Y-28521D01*
X290070Y-28509D01*
X290055Y-28492D01*
X290026Y-28466D01*
X290018Y-28458D01*
X290013Y-28452D01*
X289994Y-28445D01*
X289947Y-28422D01*
X289903Y-28393D01*
X289864Y-28358D01*
X289838Y-28330D01*
X289831Y-28323D01*
X289809Y-28304D01*
X289784Y-28275D01*
X289756Y-28250D01*
X289742Y-28235D01*
X289730Y-28221D01*
X289701Y-28196D01*
X289690Y-28183D01*
X289676Y-28167D01*
X289647Y-28142D01*
X289622Y-28113D01*
X289593Y-28088D01*
X289568Y-28059D01*
X289539Y-28034D01*
X289514Y-28005D01*
X289485Y-27980D01*
X289466Y-27958D01*
X289460Y-27951D01*
X289431Y-27926D01*
X289397Y-27886D01*
X289367Y-27843D01*
X289344Y-27796D01*
X289338Y-27777D01*
X289338Y-27777D01*
X289323Y-27764D01*
X289298Y-27735D01*
X289269Y-27710D01*
X289244Y-27681D01*
X289215Y-27656D01*
X289180Y-27616D01*
X289151Y-27573D01*
X289128Y-27525D01*
X289123Y-27512D01*
X289121Y-27506D01*
X289107Y-27493D01*
X289072Y-27454D01*
X289043Y-27410D01*
X289020Y-27363D01*
X289010Y-27333D01*
X288989Y-27302D01*
X288966Y-27255D01*
X288955Y-27225D01*
X288935Y-27194D01*
X288912Y-27147D01*
X288910Y-27143D01*
X288901Y-27117D01*
X288881Y-27086D01*
X288858Y-27039D01*
X288847Y-27009D01*
X288827Y-26978D01*
X288804Y-26931D01*
X288799Y-26917D01*
X288793Y-26901D01*
X288773Y-26870D01*
X288750Y-26823D01*
X288733Y-26773D01*
X288722Y-26722D01*
X288722Y-26712D01*
X288719Y-26708D01*
X288696Y-26660D01*
X288679Y-26611D01*
X288668Y-26559D01*
X288668Y-26550D01*
X288665Y-26545D01*
X288641Y-26498D01*
X288625Y-26449D01*
X288614Y-26397D01*
X288611Y-26345D01*
Y-26330D01*
X288611Y-26329D01*
X288587Y-26282D01*
X288570Y-26232D01*
X288560Y-26181D01*
X288557Y-26129D01*
Y-26075D01*
Y-26059D01*
X288557Y-26059D01*
X288533Y-26012D01*
X288516Y-25962D01*
X288506Y-25911D01*
X288503Y-25858D01*
Y-25804D01*
Y-25750D01*
Y-25696D01*
Y-25642D01*
Y-25588D01*
Y-25534D01*
Y-25480D01*
Y-25426D01*
Y-25372D01*
Y-25318D01*
Y-25264D01*
Y-25210D01*
Y-25155D01*
Y-25102D01*
Y-25047D01*
Y-24993D01*
Y-24939D01*
Y-24885D01*
Y-24831D01*
X288506Y-24779D01*
X288516Y-24727D01*
X288533Y-24678D01*
X288557Y-24631D01*
X288557Y-24630D01*
Y-24615D01*
Y-24561D01*
X288560Y-24509D01*
X288570Y-24457D01*
X288587Y-24408D01*
X288611Y-24360D01*
X288611Y-24360D01*
Y-24345D01*
X288614Y-24292D01*
X288625Y-24241D01*
X288641Y-24191D01*
X288665Y-24144D01*
X288668Y-24139D01*
X288668Y-24130D01*
X288679Y-24079D01*
X288696Y-24029D01*
X288719Y-23982D01*
X288739Y-23951D01*
X288741Y-23947D01*
X288750Y-23921D01*
X288773Y-23874D01*
X288776Y-23869D01*
X288776Y-23860D01*
X288787Y-23808D01*
X288804Y-23759D01*
X288827Y-23712D01*
X288847Y-23681D01*
X288849Y-23677D01*
X288858Y-23651D01*
X288881Y-23604D01*
X288901Y-23573D01*
X288903Y-23569D01*
X288912Y-23542D01*
X288935Y-23495D01*
X288955Y-23465D01*
X288966Y-23434D01*
X288989Y-23387D01*
X289018Y-23344D01*
X289053Y-23304D01*
X289067Y-23291D01*
X289074Y-23272D01*
X289097Y-23225D01*
X289126Y-23181D01*
X289161Y-23142D01*
X289176Y-23129D01*
X289182Y-23110D01*
X289205Y-23063D01*
X289234Y-23019D01*
X289269Y-22980D01*
X289298Y-22955D01*
X289323Y-22926D01*
X289326Y-22923D01*
X289352Y-22901D01*
X289377Y-22872D01*
X289392Y-22859D01*
X289398Y-22840D01*
X289422Y-22793D01*
X289451Y-22749D01*
X289485Y-22710D01*
X289488Y-22707D01*
X289514Y-22684D01*
X289539Y-22656D01*
X289568Y-22630D01*
X289593Y-22602D01*
X289622Y-22576D01*
X289647Y-22547D01*
X289658Y-22538D01*
X289676Y-22522D01*
X289701Y-22493D01*
X289730Y-22468D01*
X289756Y-22439D01*
X289795Y-22405D01*
X289839Y-22376D01*
X289885Y-22352D01*
X289905Y-22346D01*
X289918Y-22331D01*
X289946Y-22306D01*
X289972Y-22277D01*
X290001Y-22252D01*
X290026Y-22223D01*
X290065Y-22188D01*
X290109Y-22159D01*
X290156Y-22136D01*
X290167Y-22132D01*
X290175Y-22130D01*
X290188Y-22115D01*
X290227Y-22080D01*
X290271Y-22051D01*
X290318Y-22028D01*
X290337Y-22021D01*
X290350Y-22007D01*
X290390Y-21972D01*
X290433Y-21943D01*
X290480Y-21920D01*
X290511Y-21910D01*
X290541Y-21889D01*
X290588Y-21866D01*
X290599Y-21862D01*
X290619Y-21856D01*
X290649Y-21835D01*
X290697Y-21812D01*
X290727Y-21802D01*
X290758Y-21781D01*
X290805Y-21758D01*
X290835Y-21747D01*
X290866Y-21727D01*
X290913Y-21704D01*
X290962Y-21687D01*
X291014Y-21677D01*
X291023Y-21676D01*
X291028Y-21673D01*
X291075Y-21650D01*
X291125Y-21633D01*
X291176Y-21622D01*
X291185Y-21622D01*
X291190Y-21619D01*
X291237Y-21596D01*
X291287Y-21579D01*
X291338Y-21568D01*
X291348Y-21568D01*
X291352Y-21565D01*
X291399Y-21542D01*
X291449Y-21525D01*
X291500Y-21514D01*
X291553Y-21511D01*
X291568D01*
X291568Y-21511D01*
X291616Y-21487D01*
X291665Y-21471D01*
X291717Y-21460D01*
X291769Y-21457D01*
X291946D01*
X291947Y-21456D01*
X291994Y-21433D01*
X292044Y-21417D01*
X292095Y-21406D01*
X292147Y-21403D01*
X292201D01*
X292229Y-21405D01*
X292255Y-21403D01*
X334818D01*
X334818Y-21403D01*
X334865Y-21379D01*
X334915Y-21362D01*
X334966Y-21352D01*
X335018Y-21349D01*
X335088D01*
X335088Y-21348D01*
X335135Y-21325D01*
X335185Y-21308D01*
X335237Y-21298D01*
X335289Y-21295D01*
X335304D01*
X335305Y-21294D01*
X335352Y-21271D01*
X335401Y-21254D01*
X335453Y-21244D01*
X335462Y-21244D01*
X335467Y-21240D01*
X335514Y-21217D01*
X335563Y-21200D01*
X335615Y-21190D01*
X335624Y-21189D01*
X335629Y-21186D01*
X335676Y-21163D01*
X335706Y-21153D01*
X335737Y-21132D01*
X335784Y-21109D01*
X335814Y-21099D01*
X335845Y-21078D01*
X335892Y-21055D01*
X335923Y-21045D01*
X335953Y-21024D01*
X336000Y-21001D01*
X336031Y-20991D01*
X336062Y-20970D01*
X336109Y-20947D01*
X336128Y-20940D01*
X336141Y-20926D01*
X336180Y-20891D01*
X336224Y-20862D01*
X336271Y-20839D01*
X336276Y-20837D01*
X336290Y-20832D01*
X336303Y-20817D01*
X336342Y-20783D01*
X336386Y-20754D01*
X336433Y-20730D01*
X336452Y-20724D01*
X336465Y-20709D01*
X336494Y-20684D01*
X336519Y-20655D01*
X336548Y-20630D01*
X336573Y-20601D01*
X336602Y-20576D01*
X336627Y-20547D01*
X336656Y-20522D01*
X336681Y-20493D01*
X336684Y-20490D01*
X336710Y-20468D01*
X336735Y-20439D01*
X336764Y-20414D01*
X336789Y-20385D01*
X336818Y-20360D01*
X336843Y-20331D01*
X336860Y-20316D01*
X336872Y-20306D01*
X336898Y-20277D01*
X336926Y-20252D01*
X336952Y-20223D01*
X336966Y-20210D01*
X336973Y-20191D01*
X336996Y-20144D01*
X337025Y-20100D01*
X337060Y-20061D01*
X337074Y-20048D01*
X337081Y-20028D01*
X337104Y-19981D01*
X337133Y-19938D01*
X337168Y-19898D01*
X337183Y-19885D01*
X337189Y-19866D01*
X337212Y-19819D01*
X337233Y-19788D01*
X337243Y-19758D01*
X337266Y-19711D01*
X337282Y-19688D01*
X337287Y-19680D01*
X337297Y-19650D01*
X337320Y-19603D01*
X337341Y-19572D01*
X337351Y-19542D01*
X337374Y-19495D01*
X337385Y-19479D01*
X337395Y-19464D01*
X337399Y-19451D01*
X337405Y-19434D01*
X337428Y-19387D01*
X337432Y-19382D01*
X337432Y-19373D01*
X337443Y-19321D01*
X337459Y-19272D01*
X337483Y-19225D01*
X337486Y-19220D01*
X337486Y-19210D01*
X337497Y-19159D01*
X337513Y-19109D01*
X337537Y-19062D01*
X337537Y-19062D01*
Y-19047D01*
X337541Y-18994D01*
X337551Y-18943D01*
X337567Y-18893D01*
X337591Y-18846D01*
X337591Y-18846D01*
Y-18830D01*
Y-18776D01*
Y-18722D01*
X337595Y-18670D01*
X337605Y-18618D01*
X337622Y-18569D01*
X337645Y-18522D01*
X337645Y-18521D01*
Y-18506D01*
Y-18452D01*
Y-18398D01*
Y-18344D01*
Y-18290D01*
Y-18236D01*
Y-18181D01*
Y-18127D01*
Y-18073D01*
Y-18058D01*
X337645Y-18058D01*
X337622Y-18011D01*
X337605Y-17961D01*
X337595Y-17910D01*
X337591Y-17857D01*
Y-17803D01*
Y-17749D01*
Y-17734D01*
X337591Y-17733D01*
X337567Y-17686D01*
X337551Y-17637D01*
X337541Y-17585D01*
X337537Y-17533D01*
Y-17517D01*
X337537Y-17517D01*
X337513Y-17470D01*
X337497Y-17420D01*
X337486Y-17369D01*
X337486Y-17359D01*
X337483Y-17355D01*
X337459Y-17308D01*
X337449Y-17278D01*
X337428Y-17247D01*
X337405Y-17200D01*
X337388Y-17150D01*
X337378Y-17099D01*
X337378Y-17089D01*
X337374Y-17085D01*
X337351Y-17038D01*
X337341Y-17007D01*
X337320Y-16976D01*
X337297Y-16929D01*
X337287Y-16899D01*
X337266Y-16868D01*
X337243Y-16821D01*
X337240Y-16811D01*
X337237Y-16802D01*
X337222Y-16789D01*
X337187Y-16750D01*
X337158Y-16706D01*
X337135Y-16659D01*
X337128Y-16640D01*
X337114Y-16627D01*
X337079Y-16588D01*
X337050Y-16544D01*
X337027Y-16497D01*
X337020Y-16478D01*
X337006Y-16465D01*
X336980Y-16436D01*
X336952Y-16411D01*
X336917Y-16371D01*
X336888Y-16328D01*
X336865Y-16281D01*
X336863Y-16276D01*
X336858Y-16261D01*
X336843Y-16248D01*
X336818Y-16220D01*
X336789Y-16194D01*
X336764Y-16165D01*
X336735Y-16140D01*
X336710Y-16112D01*
X336681Y-16086D01*
X336656Y-16058D01*
X336627Y-16032D01*
X336614Y-16017D01*
X336595Y-16011D01*
X336548Y-15988D01*
X336505Y-15959D01*
X336465Y-15924D01*
X336440Y-15895D01*
X336411Y-15870D01*
X336400Y-15857D01*
X336386Y-15841D01*
X336357Y-15816D01*
X336347Y-15805D01*
X336344Y-15801D01*
X336325Y-15795D01*
X336278Y-15771D01*
X336247Y-15751D01*
X336217Y-15741D01*
X336170Y-15718D01*
X336126Y-15688D01*
X336087Y-15654D01*
X336074Y-15639D01*
X336054Y-15632D01*
X336007Y-15609D01*
X335997Y-15602D01*
X335977Y-15589D01*
X335946Y-15578D01*
X335899Y-15555D01*
X335885Y-15546D01*
X335869Y-15535D01*
X335838Y-15524D01*
X335791Y-15501D01*
X335760Y-15481D01*
X335730Y-15470D01*
X335683Y-15447D01*
X335678Y-15444D01*
X335669Y-15443D01*
X335618Y-15433D01*
X335568Y-15416D01*
X335521Y-15393D01*
X335490Y-15372D01*
X335460Y-15362D01*
X335413Y-15339D01*
X335412Y-15339D01*
X335397D01*
X335345Y-15335D01*
X335293Y-15325D01*
X335244Y-15308D01*
X335196Y-15285D01*
X335196Y-15285D01*
X335181D01*
X335128Y-15281D01*
X335077Y-15271D01*
X335027Y-15254D01*
X334980Y-15231D01*
X334980Y-15231D01*
X334748D01*
X334696Y-15227D01*
X334645Y-15217D01*
X334595Y-15200D01*
X334548Y-15177D01*
X334547Y-15177D01*
X326585D01*
X326533Y-15173D01*
X326481Y-15163D01*
X326431Y-15146D01*
X326384Y-15123D01*
X326384Y-15122D01*
X326260D01*
X326208Y-15119D01*
X326157Y-15109D01*
X326107Y-15092D01*
X326060Y-15069D01*
X326055Y-15066D01*
X326046Y-15065D01*
X325994Y-15055D01*
X325945Y-15038D01*
X325898Y-15015D01*
X325897Y-15014D01*
X325882D01*
X325830Y-15011D01*
X325778Y-15001D01*
X325729Y-14984D01*
X325682Y-14961D01*
X325661Y-14947D01*
X325651Y-14940D01*
X325621Y-14930D01*
X325573Y-14907D01*
X325569Y-14903D01*
X325559Y-14903D01*
X325508Y-14893D01*
X325458Y-14876D01*
X325411Y-14852D01*
X325380Y-14832D01*
X325350Y-14822D01*
X325303Y-14798D01*
X325281Y-14784D01*
X325272Y-14778D01*
X325271Y-14777D01*
X325242Y-14767D01*
X325195Y-14744D01*
X325164Y-14724D01*
X325134Y-14714D01*
X325087Y-14690D01*
X325043Y-14661D01*
X325004Y-14627D01*
X324991Y-14612D01*
X324991Y-14612D01*
X324972Y-14605D01*
X324925Y-14582D01*
X324881Y-14553D01*
X324842Y-14518D01*
X324829Y-14504D01*
X324810Y-14497D01*
X324763Y-14474D01*
X324719Y-14445D01*
X324680Y-14410D01*
X324674Y-14404D01*
X324654Y-14381D01*
X324625Y-14356D01*
X324613Y-14342D01*
X324612Y-14341D01*
X324593Y-14335D01*
X324546Y-14312D01*
X324503Y-14283D01*
X324463Y-14248D01*
X324453Y-14237D01*
X324438Y-14219D01*
X324409Y-14194D01*
X324384Y-14165D01*
X324355Y-14140D01*
X324330Y-14111D01*
X324301Y-14086D01*
X324276Y-14057D01*
X324247Y-14032D01*
X324222Y-14003D01*
X324193Y-13978D01*
X324185Y-13969D01*
X324168Y-13949D01*
X324139Y-13924D01*
X324129Y-13912D01*
X324114Y-13895D01*
X324085Y-13870D01*
X324060Y-13841D01*
X324031Y-13816D01*
X323996Y-13776D01*
X323967Y-13733D01*
X323944Y-13686D01*
X323942Y-13681D01*
X323937Y-13666D01*
X323923Y-13654D01*
X323897Y-13625D01*
X323869Y-13599D01*
X323834Y-13560D01*
X323805Y-13516D01*
X323782Y-13469D01*
X323775Y-13450D01*
X323761Y-13437D01*
X323726Y-13398D01*
X323697Y-13354D01*
X323674Y-13307D01*
X323667Y-13288D01*
X323652Y-13275D01*
X323618Y-13236D01*
X323589Y-13192D01*
X323566Y-13145D01*
X323555Y-13115D01*
X323535Y-13084D01*
X323511Y-13037D01*
X323501Y-13007D01*
X323481Y-12976D01*
X323457Y-12929D01*
X323447Y-12899D01*
X323427Y-12868D01*
X323403Y-12821D01*
X323386Y-12771D01*
X323376Y-12720D01*
X323376Y-12710D01*
X323372Y-12706D01*
X323349Y-12658D01*
X323332Y-12609D01*
X323322Y-12557D01*
X323322Y-12548D01*
X323318Y-12543D01*
X323295Y-12496D01*
X323278Y-12447D01*
X323268Y-12395D01*
X323268Y-12386D01*
X323264Y-12381D01*
X323241Y-12334D01*
X323224Y-12284D01*
X323214Y-12233D01*
X323211Y-12181D01*
Y-12165D01*
X323210Y-12165D01*
X323187Y-12118D01*
X323170Y-12068D01*
X323160Y-12017D01*
X323156Y-11964D01*
Y-11910D01*
Y-11856D01*
Y-11802D01*
Y-11787D01*
X323156Y-11786D01*
X323133Y-11739D01*
X323116Y-11690D01*
X323106Y-11638D01*
X323102Y-11586D01*
Y-11532D01*
X323104Y-11505D01*
X323102Y-11478D01*
Y-11424D01*
Y-11370D01*
Y-11316D01*
Y-11262D01*
Y-11208D01*
Y-11153D01*
Y-11099D01*
Y-11045D01*
Y-10991D01*
Y-10937D01*
D01*
Y-10883D01*
X323106Y-10831D01*
X323116Y-10779D01*
X323133Y-10730D01*
X323156Y-10683D01*
X323156Y-10682D01*
Y-10667D01*
Y-10613D01*
Y-10559D01*
X323160Y-10507D01*
X323170Y-10455D01*
X323187Y-10405D01*
X323210Y-10358D01*
X323211Y-10358D01*
Y-10343D01*
X323214Y-10290D01*
X323224Y-10239D01*
X323241Y-10189D01*
X323264Y-10142D01*
X323268Y-10137D01*
X323268Y-10128D01*
X323278Y-10077D01*
X323295Y-10027D01*
X323318Y-9980D01*
X323322Y-9975D01*
X323322Y-9966D01*
X323332Y-9914D01*
X323349Y-9865D01*
X323372Y-9818D01*
X323376Y-9813D01*
X323376Y-9804D01*
X323386Y-9752D01*
X323403Y-9703D01*
X323427Y-9656D01*
X323447Y-9625D01*
X323448Y-9621D01*
X323457Y-9595D01*
X323481Y-9547D01*
X323491Y-9532D01*
X323501Y-9517D01*
X323511Y-9486D01*
X323535Y-9439D01*
X323555Y-9409D01*
X323566Y-9378D01*
X323589Y-9331D01*
X323618Y-9288D01*
X323652Y-9248D01*
X323667Y-9235D01*
X323674Y-9216D01*
X323697Y-9169D01*
X323717Y-9138D01*
X323728Y-9108D01*
X323751Y-9061D01*
X323780Y-9017D01*
X323815Y-8978D01*
X323843Y-8953D01*
X323869Y-8924D01*
X323871Y-8921D01*
X323883Y-8911D01*
X323890Y-8892D01*
X323913Y-8845D01*
X323942Y-8801D01*
X323977Y-8762D01*
X324006Y-8736D01*
X324031Y-8708D01*
X324060Y-8682D01*
X324085Y-8653D01*
X324114Y-8628D01*
X324139Y-8599D01*
X324168Y-8574D01*
X324193Y-8545D01*
X324222Y-8520D01*
X324247Y-8491D01*
X324276Y-8466D01*
X324301Y-8437D01*
X324330Y-8412D01*
X324355Y-8383D01*
X324384Y-8358D01*
X324409Y-8329D01*
X324438Y-8304D01*
X324463Y-8275D01*
X324492Y-8250D01*
X324517Y-8221D01*
X324557Y-8186D01*
X324600Y-8157D01*
X324647Y-8134D01*
X324667Y-8128D01*
X324680Y-8113D01*
X324708Y-8088D01*
X324734Y-8059D01*
X324773Y-8024D01*
X324817Y-7995D01*
X324864Y-7972D01*
X324883Y-7965D01*
X324896Y-7951D01*
X324935Y-7916D01*
X324979Y-7887D01*
X325026Y-7864D01*
X325056Y-7853D01*
X325087Y-7833D01*
X325134Y-7810D01*
X325164Y-7799D01*
X325195Y-7779D01*
X325242Y-7756D01*
X325272Y-7745D01*
X325303Y-7725D01*
X325350Y-7702D01*
X325380Y-7691D01*
X325411Y-7671D01*
X325458Y-7648D01*
X325489Y-7637D01*
X325519Y-7617D01*
X325567Y-7593D01*
X325616Y-7577D01*
X325668Y-7566D01*
X325677Y-7566D01*
X325682Y-7563D01*
X325729Y-7539D01*
X325778Y-7523D01*
X325830Y-7512D01*
X325839Y-7512D01*
X325844Y-7508D01*
X325891Y-7485D01*
X325940Y-7468D01*
X325992Y-7458D01*
X326044Y-7455D01*
X326060D01*
X326060Y-7455D01*
X326107Y-7431D01*
X326157Y-7414D01*
X326208Y-7404D01*
X326260Y-7401D01*
X326276D01*
X326276Y-7400D01*
X326323Y-7377D01*
X326373Y-7360D01*
X326424Y-7350D01*
X326477Y-7347D01*
X326870D01*
X326871Y-7346D01*
X326918Y-7323D01*
X326968Y-7306D01*
X327019Y-7296D01*
X327071Y-7293D01*
X395298D01*
X395350Y-7296D01*
D02*
G37*
G36*
X393566Y-29894D02*
X393617Y-29904D01*
X393667Y-29921D01*
X393714Y-29944D01*
X393715Y-29945D01*
X393730D01*
X393782Y-29948D01*
X393834Y-29958D01*
X393883Y-29975D01*
X393930Y-29998D01*
X393961Y-30019D01*
X393991Y-30029D01*
X394038Y-30052D01*
X394043Y-30056D01*
X394053Y-30056D01*
X394104Y-30066D01*
X394154Y-30083D01*
X394201Y-30106D01*
X394231Y-30127D01*
X394262Y-30137D01*
X394309Y-30160D01*
X394352Y-30190D01*
X394392Y-30224D01*
X394405Y-30239D01*
X394424Y-30245D01*
X394471Y-30269D01*
X394514Y-30298D01*
X394554Y-30332D01*
X394579Y-30361D01*
X394608Y-30386D01*
X394621Y-30401D01*
X394640Y-30408D01*
X394687Y-30431D01*
X394731Y-30460D01*
X394770Y-30494D01*
X394795Y-30523D01*
X394824Y-30549D01*
X394849Y-30577D01*
X394878Y-30603D01*
X394904Y-30632D01*
X394932Y-30657D01*
X394967Y-30696D01*
X394996Y-30740D01*
X395019Y-30787D01*
X395026Y-30806D01*
X395040Y-30819D01*
X395066Y-30848D01*
X395095Y-30873D01*
X395129Y-30912D01*
X395158Y-30956D01*
X395181Y-31003D01*
X395192Y-31033D01*
X395212Y-31064D01*
X395235Y-31111D01*
X395246Y-31141D01*
X395266Y-31172D01*
X395290Y-31219D01*
X395300Y-31250D01*
X395304Y-31256D01*
X395321Y-31280D01*
X395344Y-31327D01*
X395354Y-31357D01*
X395354Y-31358D01*
X395361Y-31368D01*
X395374Y-31389D01*
X395398Y-31435D01*
X395415Y-31485D01*
X395425Y-31537D01*
X395425Y-31546D01*
X395429Y-31551D01*
X395452Y-31598D01*
X395469Y-31647D01*
X395479Y-31699D01*
X395482Y-31751D01*
Y-31805D01*
Y-31820D01*
X395483Y-31821D01*
X395506Y-31868D01*
X395523Y-31918D01*
X395533Y-31969D01*
X395536Y-32021D01*
Y-32076D01*
Y-32129D01*
Y-32184D01*
Y-32238D01*
Y-32292D01*
Y-32346D01*
Y-32400D01*
Y-32454D01*
Y-32508D01*
Y-32562D01*
X395533Y-32614D01*
X395523Y-32666D01*
X395506Y-32715D01*
X395483Y-32763D01*
X395482Y-32763D01*
Y-32778D01*
Y-32832D01*
X395479Y-32885D01*
X395469Y-32936D01*
X395452Y-32986D01*
X395429Y-33033D01*
X395425Y-33037D01*
X395425Y-33047D01*
X395415Y-33098D01*
X395398Y-33148D01*
X395374Y-33195D01*
X395371Y-33200D01*
X395371Y-33209D01*
X395360Y-33261D01*
X395344Y-33310D01*
X395321Y-33357D01*
X395300Y-33388D01*
X395290Y-33418D01*
X395266Y-33465D01*
X395237Y-33509D01*
X395203Y-33548D01*
X395188Y-33561D01*
X395181Y-33580D01*
X395158Y-33628D01*
X395138Y-33658D01*
X395127Y-33689D01*
X395104Y-33736D01*
X395075Y-33779D01*
X395040Y-33819D01*
X395012Y-33844D01*
X394991Y-33868D01*
X394987Y-33873D01*
X394961Y-33895D01*
X394958Y-33898D01*
X394932Y-33927D01*
X394903Y-33952D01*
X394878Y-33981D01*
X394849Y-34006D01*
X394824Y-34035D01*
X394795Y-34060D01*
X394770Y-34089D01*
X394741Y-34114D01*
X394716Y-34143D01*
X394687Y-34168D01*
X394662Y-34197D01*
X394623Y-34232D01*
X394579Y-34261D01*
X394532Y-34284D01*
X394513Y-34291D01*
X394500Y-34305D01*
X394461Y-34340D01*
X394417Y-34369D01*
X394370Y-34392D01*
X394351Y-34399D01*
X394338Y-34413D01*
X394298Y-34448D01*
X394255Y-34477D01*
X394208Y-34500D01*
X394158Y-34517D01*
X394107Y-34527D01*
X394097Y-34528D01*
X394092Y-34531D01*
X394045Y-34554D01*
X394015Y-34565D01*
X393984Y-34585D01*
X393937Y-34608D01*
X393888Y-34625D01*
X393836Y-34635D01*
X393827Y-34636D01*
D01*
X393822Y-34639D01*
X393775Y-34662D01*
X393725Y-34679D01*
X393674Y-34689D01*
X393622Y-34693D01*
X393498D01*
X393498Y-34693D01*
X393451Y-34716D01*
X393401Y-34733D01*
X393350Y-34743D01*
X393297Y-34747D01*
X392919D01*
X392867Y-34743D01*
X392815Y-34733D01*
X392765Y-34716D01*
X392719Y-34693D01*
X392718Y-34693D01*
X392595D01*
X392542Y-34689D01*
X392491Y-34679D01*
X392441Y-34662D01*
X392394Y-34639D01*
X392389Y-34636D01*
X392380Y-34635D01*
X392329Y-34625D01*
X392279Y-34608D01*
X392232Y-34585D01*
X392227Y-34582D01*
X392218Y-34581D01*
X392166Y-34571D01*
X392117Y-34554D01*
X392070Y-34531D01*
X392039Y-34510D01*
X392009Y-34500D01*
X391962Y-34477D01*
X391931Y-34456D01*
X391901Y-34446D01*
X391853Y-34423D01*
X391810Y-34394D01*
X391771Y-34359D01*
X391758Y-34345D01*
X391738Y-34338D01*
X391691Y-34315D01*
X391648Y-34286D01*
X391608Y-34251D01*
X391583Y-34222D01*
X391554Y-34197D01*
X391550Y-34193D01*
X391529Y-34168D01*
X391500Y-34143D01*
X391495Y-34137D01*
X391475Y-34114D01*
X391446Y-34089D01*
X391421Y-34060D01*
X391392Y-34035D01*
X391367Y-34006D01*
X391338Y-33981D01*
X391313Y-33952D01*
X391284Y-33927D01*
X391259Y-33898D01*
X391255Y-33895D01*
X391230Y-33873D01*
X391205Y-33844D01*
X391176Y-33819D01*
X391141Y-33779D01*
X391112Y-33736D01*
X391089Y-33689D01*
X391082Y-33669D01*
X391068Y-33656D01*
X391033Y-33617D01*
X391004Y-33573D01*
X390981Y-33526D01*
X390970Y-33496D01*
X390950Y-33465D01*
X390927Y-33418D01*
X390916Y-33388D01*
X390896Y-33357D01*
X390873Y-33310D01*
X390862Y-33280D01*
X390842Y-33249D01*
X390819Y-33202D01*
X390802Y-33152D01*
X390792Y-33101D01*
X390791Y-33094D01*
X390791Y-33092D01*
X390788Y-33087D01*
X390765Y-33040D01*
X390748Y-32990D01*
X390738Y-32939D01*
X390734Y-32886D01*
Y-32871D01*
X390734Y-32871D01*
X390710Y-32824D01*
X390694Y-32774D01*
X390683Y-32722D01*
X390680Y-32670D01*
Y-32616D01*
Y-32562D01*
Y-32508D01*
Y-32454D01*
Y-32400D01*
Y-32346D01*
Y-32292D01*
Y-32238D01*
Y-32184D01*
Y-32129D01*
Y-32076D01*
Y-32021D01*
Y-31967D01*
X390683Y-31915D01*
X390694Y-31864D01*
X390710Y-31814D01*
X390734Y-31767D01*
X390734Y-31766D01*
Y-31751D01*
X390738Y-31699D01*
X390748Y-31647D01*
X390765Y-31598D01*
X390788Y-31551D01*
X390791Y-31546D01*
X390792Y-31537D01*
X390802Y-31485D01*
X390819Y-31435D01*
X390842Y-31389D01*
X390845Y-31384D01*
X390846Y-31374D01*
X390856Y-31323D01*
X390873Y-31273D01*
X390896Y-31226D01*
X390916Y-31196D01*
X390927Y-31165D01*
X390950Y-31118D01*
X390979Y-31075D01*
X391014Y-31035D01*
X391028Y-31022D01*
X391035Y-31003D01*
X391058Y-30956D01*
X391087Y-30912D01*
X391122Y-30873D01*
X391137Y-30860D01*
X391143Y-30841D01*
X391166Y-30794D01*
X391195Y-30750D01*
X391230Y-30711D01*
X391259Y-30685D01*
X391284Y-30657D01*
X391313Y-30632D01*
X391338Y-30603D01*
X391367Y-30577D01*
X391392Y-30549D01*
X391421Y-30523D01*
X391446Y-30494D01*
X391475Y-30469D01*
X391500Y-30441D01*
X391540Y-30406D01*
X391583Y-30377D01*
X391630Y-30354D01*
X391650Y-30347D01*
X391662Y-30332D01*
X391702Y-30298D01*
X391745Y-30269D01*
X391792Y-30245D01*
X391812Y-30239D01*
X391825Y-30224D01*
X391864Y-30190D01*
X391908Y-30160D01*
X391955Y-30137D01*
X391985Y-30127D01*
X392016Y-30106D01*
X392063Y-30083D01*
X392093Y-30073D01*
X392124Y-30052D01*
X392171Y-30029D01*
X392220Y-30012D01*
X392272Y-30002D01*
X392281Y-30002D01*
X392286Y-29998D01*
X392333Y-29975D01*
X392383Y-29958D01*
X392434Y-29948D01*
X392487Y-29945D01*
X392502D01*
X392502Y-29944D01*
X392549Y-29921D01*
X392599Y-29904D01*
X392650Y-29894D01*
X392703Y-29891D01*
X393514D01*
X393566Y-29894D01*
D02*
G37*
G36*
X393458Y-37192D02*
X393509Y-37203D01*
X393559Y-37220D01*
X393606Y-37243D01*
X393606Y-37243D01*
X393676D01*
X393728Y-37246D01*
X393780Y-37257D01*
X393829Y-37273D01*
X393876Y-37297D01*
X393881Y-37300D01*
X393890Y-37301D01*
X393942Y-37311D01*
X393991Y-37328D01*
X394038Y-37351D01*
X394069Y-37371D01*
X394099Y-37382D01*
X394147Y-37405D01*
X394177Y-37425D01*
X394208Y-37436D01*
X394255Y-37459D01*
X394285Y-37479D01*
X394316Y-37490D01*
X394363Y-37513D01*
X394406Y-37542D01*
X394446Y-37577D01*
X394459Y-37591D01*
X394478Y-37598D01*
X394525Y-37621D01*
X394569Y-37650D01*
X394608Y-37685D01*
X394633Y-37714D01*
X394662Y-37739D01*
X394687Y-37768D01*
X394716Y-37793D01*
X394741Y-37822D01*
X394770Y-37847D01*
X394795Y-37876D01*
X394824Y-37901D01*
X394849Y-37930D01*
X394878Y-37955D01*
X394903Y-37984D01*
X394932Y-38009D01*
X394958Y-38038D01*
X394987Y-38063D01*
X395012Y-38092D01*
X395040Y-38117D01*
X395075Y-38157D01*
X395104Y-38200D01*
X395127Y-38247D01*
X395134Y-38267D01*
X395149Y-38280D01*
X395183Y-38319D01*
X395212Y-38363D01*
X395235Y-38410D01*
X395246Y-38440D01*
X395266Y-38471D01*
X395290Y-38518D01*
X395300Y-38548D01*
X395321Y-38579D01*
X395344Y-38626D01*
X395354Y-38656D01*
X395374Y-38687D01*
X395398Y-38734D01*
X395415Y-38783D01*
X395425Y-38835D01*
X395428Y-38887D01*
Y-38903D01*
X395429Y-38903D01*
X395452Y-38950D01*
X395469Y-39000D01*
X395479Y-39051D01*
X395482Y-39103D01*
Y-39119D01*
X395483Y-39119D01*
X395506Y-39166D01*
X395523Y-39216D01*
X395533Y-39268D01*
X395536Y-39320D01*
Y-39374D01*
Y-39428D01*
Y-39482D01*
Y-39536D01*
Y-39590D01*
Y-39644D01*
Y-39698D01*
Y-39752D01*
Y-39806D01*
Y-39860D01*
Y-39915D01*
X395533Y-39967D01*
X395523Y-40018D01*
X395506Y-40068D01*
X395483Y-40115D01*
X395482Y-40115D01*
Y-40131D01*
X395479Y-40183D01*
X395469Y-40235D01*
X395452Y-40284D01*
X395429Y-40331D01*
X395425Y-40336D01*
X395425Y-40345D01*
X395415Y-40397D01*
X395398Y-40446D01*
X395374Y-40493D01*
X395371Y-40498D01*
X395371Y-40507D01*
X395360Y-40559D01*
X395344Y-40609D01*
X395321Y-40655D01*
X395300Y-40686D01*
X395296Y-40699D01*
X395290Y-40717D01*
X395266Y-40764D01*
X395246Y-40795D01*
X395240Y-40811D01*
X395235Y-40825D01*
X395212Y-40872D01*
X395183Y-40915D01*
X395149Y-40955D01*
X395134Y-40968D01*
X395127Y-40987D01*
X395104Y-41034D01*
X395075Y-41078D01*
X395040Y-41117D01*
X395012Y-41142D01*
X394987Y-41171D01*
X394958Y-41196D01*
X394932Y-41225D01*
X394903Y-41250D01*
X394878Y-41279D01*
X394849Y-41304D01*
X394824Y-41333D01*
X394795Y-41359D01*
X394770Y-41387D01*
X394741Y-41412D01*
X394716Y-41441D01*
X394687Y-41467D01*
X394662Y-41495D01*
X394633Y-41521D01*
X394608Y-41550D01*
X394569Y-41584D01*
X394525Y-41613D01*
X394478Y-41636D01*
X394459Y-41643D01*
X394446Y-41658D01*
X394406Y-41692D01*
X394363Y-41721D01*
X394316Y-41745D01*
X394285Y-41755D01*
X394255Y-41775D01*
X394208Y-41799D01*
X394177Y-41809D01*
X394147Y-41829D01*
X394099Y-41853D01*
X394069Y-41863D01*
X394038Y-41884D01*
X393991Y-41907D01*
X393942Y-41923D01*
X393890Y-41934D01*
X393881Y-41934D01*
X393876Y-41938D01*
X393829Y-41961D01*
X393780Y-41978D01*
X393728Y-41988D01*
X393676Y-41991D01*
X393606D01*
X393606Y-41992D01*
X393559Y-42015D01*
X393509Y-42032D01*
X393458Y-42042D01*
X393406Y-42045D01*
X392811D01*
X392758Y-42042D01*
X392707Y-42032D01*
X392657Y-42015D01*
X392610Y-41992D01*
X392610Y-41991D01*
X392541D01*
X392488Y-41988D01*
X392437Y-41978D01*
X392387Y-41961D01*
X392340Y-41938D01*
X392335Y-41934D01*
X392326Y-41934D01*
X392275Y-41923D01*
X392225Y-41907D01*
X392178Y-41884D01*
X392147Y-41863D01*
X392117Y-41853D01*
X392070Y-41829D01*
X392039Y-41809D01*
X392009Y-41799D01*
X391962Y-41775D01*
X391931Y-41755D01*
X391931D01*
X391901Y-41745D01*
X391853Y-41721D01*
X391823Y-41701D01*
X391792Y-41690D01*
X391745Y-41667D01*
X391702Y-41638D01*
X391662Y-41603D01*
X391637Y-41575D01*
X391608Y-41550D01*
X391583Y-41521D01*
X391554Y-41495D01*
X391541Y-41481D01*
X391522Y-41474D01*
X391475Y-41451D01*
X391431Y-41422D01*
X391392Y-41387D01*
X391377Y-41370D01*
X391367Y-41359D01*
X391338Y-41333D01*
X391313Y-41304D01*
X391284Y-41279D01*
X391249Y-41240D01*
X391220Y-41196D01*
X391197Y-41149D01*
X391191Y-41130D01*
X391176Y-41117D01*
X391151Y-41088D01*
X391122Y-41063D01*
X391087Y-41023D01*
X391058Y-40980D01*
X391035Y-40933D01*
X391025Y-40903D01*
X391004Y-40872D01*
X390981Y-40825D01*
X390970Y-40794D01*
X390950Y-40764D01*
X390927Y-40717D01*
X390916Y-40686D01*
X390896Y-40655D01*
X390873Y-40609D01*
X390862Y-40578D01*
X390842Y-40547D01*
X390819Y-40500D01*
X390802Y-40451D01*
X390792Y-40399D01*
X390791Y-40390D01*
X390788Y-40385D01*
X390765Y-40338D01*
X390748Y-40288D01*
X390738Y-40237D01*
X390734Y-40185D01*
Y-40170D01*
X390734Y-40169D01*
X390710Y-40122D01*
X390694Y-40072D01*
X390683Y-40021D01*
X390680Y-39968D01*
Y-39915D01*
Y-39860D01*
Y-39806D01*
Y-39752D01*
Y-39698D01*
Y-39644D01*
Y-39590D01*
Y-39536D01*
Y-39482D01*
Y-39428D01*
Y-39374D01*
Y-39320D01*
Y-39266D01*
X390683Y-39213D01*
X390694Y-39162D01*
X390710Y-39112D01*
X390734Y-39065D01*
X390734Y-39065D01*
Y-39050D01*
X390738Y-38997D01*
X390748Y-38946D01*
X390765Y-38896D01*
X390788Y-38849D01*
X390791Y-38844D01*
X390792Y-38835D01*
X390802Y-38783D01*
X390819Y-38734D01*
X390842Y-38687D01*
X390862Y-38656D01*
X390873Y-38626D01*
X390896Y-38579D01*
X390916Y-38548D01*
X390927Y-38518D01*
X390950Y-38471D01*
X390970Y-38440D01*
X390981Y-38410D01*
X391004Y-38363D01*
X391016Y-38345D01*
X391025Y-38332D01*
X391025Y-38331D01*
X391035Y-38301D01*
X391058Y-38254D01*
X391087Y-38211D01*
X391122Y-38171D01*
X391151Y-38146D01*
X391176Y-38117D01*
X391191Y-38104D01*
X391197Y-38085D01*
X391220Y-38038D01*
X391249Y-37995D01*
X391284Y-37955D01*
X391313Y-37930D01*
X391338Y-37901D01*
X391367Y-37876D01*
X391392Y-37847D01*
X391421Y-37822D01*
X391446Y-37793D01*
X391486Y-37758D01*
X391529Y-37729D01*
X391576Y-37706D01*
X391595Y-37699D01*
X391608Y-37685D01*
X391637Y-37659D01*
X391662Y-37631D01*
X391702Y-37596D01*
X391745Y-37567D01*
X391792Y-37544D01*
X391798Y-37542D01*
X391823Y-37534D01*
X391853Y-37513D01*
X391901Y-37490D01*
X391931Y-37479D01*
X391962Y-37459D01*
X392009Y-37436D01*
X392039Y-37425D01*
X392070Y-37405D01*
X392117Y-37382D01*
X392147Y-37371D01*
X392178Y-37351D01*
X392225Y-37328D01*
X392275Y-37311D01*
X392326Y-37301D01*
X392335Y-37300D01*
X392340Y-37297D01*
X392387Y-37273D01*
X392437Y-37257D01*
X392488Y-37246D01*
X392541Y-37243D01*
X392556D01*
X392556Y-37243D01*
X392603Y-37220D01*
X392653Y-37203D01*
X392704Y-37192D01*
X392757Y-37189D01*
X393406D01*
X393458Y-37192D01*
D02*
G37*
G36*
X299390Y-35516D02*
X299441Y-35527D01*
X299491Y-35544D01*
X299538Y-35567D01*
X299539Y-35567D01*
X299608D01*
X299660Y-35570D01*
X299712Y-35581D01*
X299761Y-35598D01*
X299808Y-35621D01*
X299809Y-35621D01*
X299824D01*
X299876Y-35625D01*
X299928Y-35635D01*
X299978Y-35652D01*
X300025Y-35675D01*
X300029Y-35678D01*
X300039Y-35679D01*
X300090Y-35689D01*
X300140Y-35706D01*
X300187Y-35729D01*
X300191Y-35732D01*
X300201Y-35733D01*
X300252Y-35743D01*
X300302Y-35760D01*
X300349Y-35783D01*
X300354Y-35786D01*
X300363Y-35787D01*
X300414Y-35797D01*
X300464Y-35814D01*
X300511Y-35837D01*
X300542Y-35858D01*
X300572Y-35868D01*
X300619Y-35891D01*
X300650Y-35912D01*
X300680Y-35922D01*
X300727Y-35945D01*
X300758Y-35966D01*
X300783Y-35974D01*
X300788Y-35976D01*
X300835Y-35999D01*
X300879Y-36028D01*
X300919Y-36063D01*
X300931Y-36078D01*
X300951Y-36084D01*
X300998Y-36107D01*
X301041Y-36136D01*
X301081Y-36171D01*
X301094Y-36186D01*
X301113Y-36192D01*
X301160Y-36215D01*
X301203Y-36245D01*
X301243Y-36279D01*
X301256Y-36294D01*
X301275Y-36300D01*
X301322Y-36324D01*
X301366Y-36353D01*
X301405Y-36387D01*
X301430Y-36416D01*
X301459Y-36441D01*
X301484Y-36470D01*
X301513Y-36495D01*
X301538Y-36524D01*
X301567Y-36549D01*
X301593Y-36578D01*
X301621Y-36604D01*
X301647Y-36632D01*
X301675Y-36658D01*
X301701Y-36686D01*
X301729Y-36712D01*
X301755Y-36740D01*
X301783Y-36766D01*
X301809Y-36794D01*
X301838Y-36820D01*
X301863Y-36849D01*
X301892Y-36874D01*
X301917Y-36903D01*
X301946Y-36928D01*
X301980Y-36967D01*
X302009Y-37011D01*
X302033Y-37058D01*
X302039Y-37077D01*
X302054Y-37090D01*
X302079Y-37119D01*
X302108Y-37144D01*
X302143Y-37184D01*
X302172Y-37227D01*
X302195Y-37274D01*
X302201Y-37293D01*
X302216Y-37306D01*
X302251Y-37346D01*
X302280Y-37389D01*
X302303Y-37436D01*
X302313Y-37467D01*
X302334Y-37497D01*
X302357Y-37545D01*
X302367Y-37575D01*
X302388Y-37606D01*
X302411Y-37653D01*
X302421Y-37683D01*
X302437Y-37706D01*
X302442Y-37714D01*
X302465Y-37761D01*
X302475Y-37791D01*
X302496Y-37822D01*
X302519Y-37869D01*
X302530Y-37899D01*
X302550Y-37930D01*
X302573Y-37977D01*
X302590Y-38027D01*
X302600Y-38078D01*
X302601Y-38087D01*
X302604Y-38092D01*
X302627Y-38139D01*
X302644Y-38189D01*
X302654Y-38240D01*
X302655Y-38250D01*
X302658Y-38254D01*
X302681Y-38301D01*
X302698Y-38351D01*
X302708Y-38403D01*
X302712Y-38455D01*
Y-38470D01*
X302712Y-38471D01*
X302735Y-38518D01*
X302752Y-38567D01*
X302763Y-38619D01*
X302766Y-38671D01*
Y-38725D01*
Y-38740D01*
X302766Y-38741D01*
X302789Y-38788D01*
X302806Y-38838D01*
X302817Y-38889D01*
X302820Y-38941D01*
Y-38995D01*
Y-39050D01*
Y-39103D01*
Y-39158D01*
Y-39212D01*
Y-39266D01*
Y-39320D01*
Y-39374D01*
Y-39428D01*
Y-39482D01*
Y-39536D01*
Y-39590D01*
Y-39644D01*
Y-39698D01*
Y-39752D01*
Y-39806D01*
Y-39860D01*
Y-39915D01*
Y-39968D01*
X302817Y-40021D01*
X302806Y-40072D01*
X302789Y-40122D01*
X302766Y-40169D01*
X302766Y-40170D01*
Y-40185D01*
Y-40239D01*
X302763Y-40291D01*
X302752Y-40343D01*
X302735Y-40392D01*
X302712Y-40439D01*
X302712Y-40440D01*
Y-40455D01*
X302708Y-40507D01*
X302698Y-40559D01*
X302681Y-40609D01*
X302658Y-40655D01*
X302655Y-40660D01*
X302654Y-40670D01*
X302644Y-40721D01*
X302627Y-40771D01*
X302604Y-40818D01*
X302584Y-40849D01*
X302573Y-40879D01*
X302550Y-40926D01*
X302547Y-40931D01*
X302546Y-40940D01*
X302536Y-40991D01*
X302519Y-41041D01*
X302496Y-41088D01*
X302475Y-41119D01*
X302465Y-41149D01*
X302442Y-41196D01*
X302421Y-41227D01*
X302414Y-41250D01*
X302411Y-41257D01*
X302388Y-41304D01*
X302359Y-41348D01*
X302324Y-41387D01*
X302309Y-41400D01*
X302304Y-41415D01*
X302303Y-41419D01*
X302280Y-41466D01*
X302259Y-41497D01*
X302249Y-41528D01*
X302226Y-41575D01*
X302197Y-41618D01*
X302162Y-41658D01*
X302147Y-41671D01*
X302141Y-41690D01*
X302117Y-41737D01*
X302088Y-41780D01*
X302054Y-41820D01*
X302025Y-41845D01*
X302000Y-41874D01*
X301971Y-41899D01*
X301946Y-41928D01*
X301931Y-41941D01*
X301924Y-41960D01*
X301901Y-42007D01*
X301872Y-42051D01*
X301838Y-42090D01*
X301809Y-42115D01*
X301783Y-42144D01*
X301755Y-42169D01*
X301729Y-42198D01*
X301701Y-42224D01*
X301675Y-42252D01*
X301647Y-42278D01*
X301621Y-42306D01*
X301592Y-42332D01*
X301567Y-42360D01*
X301528Y-42395D01*
X301484Y-42424D01*
X301437Y-42447D01*
X301418Y-42454D01*
X301405Y-42469D01*
X301380Y-42490D01*
X301376Y-42494D01*
X301351Y-42523D01*
X301322Y-42548D01*
X301297Y-42577D01*
X301258Y-42611D01*
X301214Y-42640D01*
X301167Y-42663D01*
X301148Y-42670D01*
X301135Y-42685D01*
X301095Y-42719D01*
X301052Y-42748D01*
X301005Y-42772D01*
X300986Y-42778D01*
X300973Y-42793D01*
X300933Y-42827D01*
X300890Y-42857D01*
X300843Y-42880D01*
X300812Y-42890D01*
X300781Y-42911D01*
X300734Y-42934D01*
X300704Y-42944D01*
X300673Y-42965D01*
X300626Y-42988D01*
X300596Y-42998D01*
X300565Y-43019D01*
X300518Y-43042D01*
X300488Y-43052D01*
X300471Y-43063D01*
X300457Y-43073D01*
X300410Y-43096D01*
X300360Y-43113D01*
X300309Y-43123D01*
X300300Y-43124D01*
X300295Y-43127D01*
X300248Y-43150D01*
X300198Y-43167D01*
X300147Y-43177D01*
X300137Y-43178D01*
X300133Y-43181D01*
X300086Y-43204D01*
X300036Y-43221D01*
X299985Y-43231D01*
X299975Y-43232D01*
X299971Y-43235D01*
X299923Y-43258D01*
X299874Y-43275D01*
X299822Y-43285D01*
X299770Y-43289D01*
X299701D01*
X299700Y-43289D01*
X299653Y-43312D01*
X299604Y-43329D01*
X299552Y-43339D01*
X299500Y-43343D01*
X299322D01*
X299322Y-43343D01*
X299275Y-43366D01*
X299225Y-43383D01*
X299174Y-43393D01*
X299121Y-43397D01*
X298743D01*
X298716Y-43395D01*
X298689Y-43397D01*
X298635D01*
X298608Y-43395D01*
X298581Y-43397D01*
X298527D01*
X298474Y-43393D01*
X298423Y-43383D01*
X298373Y-43366D01*
X298326Y-43343D01*
X298326Y-43343D01*
X298202D01*
X298150Y-43339D01*
X298099Y-43329D01*
X298049Y-43312D01*
X298002Y-43289D01*
X298001Y-43289D01*
X297932D01*
X297880Y-43285D01*
X297828Y-43275D01*
X297779Y-43258D01*
X297732Y-43235D01*
X297731Y-43235D01*
X297716D01*
X297663Y-43231D01*
X297612Y-43221D01*
X297562Y-43204D01*
X297515Y-43181D01*
X297511Y-43178D01*
X297501Y-43177D01*
X297450Y-43167D01*
X297400Y-43150D01*
X297353Y-43127D01*
X297322Y-43106D01*
X297292Y-43096D01*
X297245Y-43073D01*
X297240Y-43070D01*
X297231Y-43069D01*
X297180Y-43059D01*
X297130Y-43042D01*
X297083Y-43019D01*
X297052Y-42998D01*
X297022Y-42988D01*
X296975Y-42965D01*
X296944Y-42944D01*
X296914Y-42934D01*
X296867Y-42911D01*
X296823Y-42882D01*
X296784Y-42847D01*
X296771Y-42832D01*
X296751Y-42826D01*
X296704Y-42803D01*
X296674Y-42782D01*
X296643Y-42772D01*
X296596Y-42748D01*
X296553Y-42719D01*
X296513Y-42685D01*
X296488Y-42656D01*
X296459Y-42631D01*
X296446Y-42616D01*
X296427Y-42610D01*
X296380Y-42586D01*
X296336Y-42557D01*
X296297Y-42523D01*
X296272Y-42494D01*
X296268Y-42490D01*
X296243Y-42469D01*
X296218Y-42440D01*
X296189Y-42415D01*
X296164Y-42386D01*
X296135Y-42360D01*
X296110Y-42332D01*
X296081Y-42306D01*
X296056Y-42278D01*
X296027Y-42252D01*
X296001Y-42224D01*
X295973Y-42198D01*
X295947Y-42169D01*
X295919Y-42144D01*
X295893Y-42115D01*
X295865Y-42090D01*
X295839Y-42061D01*
X295810Y-42036D01*
X295785Y-42007D01*
X295756Y-41982D01*
X295731Y-41953D01*
X295727Y-41950D01*
X295702Y-41928D01*
X295677Y-41899D01*
X295648Y-41874D01*
X295614Y-41834D01*
X295585Y-41791D01*
X295561Y-41744D01*
X295555Y-41725D01*
X295540Y-41712D01*
X295506Y-41672D01*
X295476Y-41629D01*
X295453Y-41582D01*
X295447Y-41562D01*
X295432Y-41550D01*
X295397Y-41510D01*
X295368Y-41466D01*
X295345Y-41419D01*
X295335Y-41389D01*
X295314Y-41358D01*
X295291Y-41311D01*
X295281Y-41281D01*
X295260Y-41250D01*
X295237Y-41203D01*
X295227Y-41173D01*
X295206Y-41142D01*
X295183Y-41095D01*
X295173Y-41065D01*
X295152Y-41034D01*
X295129Y-40987D01*
X295119Y-40957D01*
X295098Y-40926D01*
X295075Y-40879D01*
X295058Y-40829D01*
X295048Y-40778D01*
X295047Y-40768D01*
X295044Y-40764D01*
X295021Y-40717D01*
X295004Y-40667D01*
X294994Y-40615D01*
X294993Y-40609D01*
X294993Y-40606D01*
X294990Y-40602D01*
X294967Y-40554D01*
X294950Y-40505D01*
X294940Y-40453D01*
X294936Y-40401D01*
Y-40386D01*
X294936Y-40385D01*
X294913Y-40338D01*
X294896Y-40288D01*
X294885Y-40237D01*
X294882Y-40185D01*
Y-40131D01*
Y-40077D01*
Y-40061D01*
X294882Y-40061D01*
X294859Y-40014D01*
X294842Y-39964D01*
X294831Y-39913D01*
X294828Y-39860D01*
Y-39806D01*
Y-39752D01*
Y-39698D01*
Y-39644D01*
Y-39590D01*
Y-39536D01*
Y-39482D01*
Y-39428D01*
Y-39374D01*
Y-39320D01*
Y-39266D01*
Y-39212D01*
Y-39158D01*
Y-39103D01*
Y-39050D01*
X294831Y-38997D01*
X294842Y-38946D01*
X294859Y-38896D01*
X294882Y-38849D01*
X294882Y-38849D01*
Y-38833D01*
Y-38779D01*
Y-38725D01*
X294885Y-38673D01*
X294896Y-38621D01*
X294913Y-38572D01*
X294936Y-38525D01*
X294936Y-38524D01*
Y-38509D01*
X294940Y-38456D01*
X294950Y-38405D01*
X294967Y-38355D01*
X294990Y-38308D01*
X294993Y-38304D01*
X294994Y-38294D01*
X295004Y-38243D01*
X295021Y-38193D01*
X295044Y-38146D01*
X295044Y-38145D01*
X295047Y-38142D01*
X295048Y-38132D01*
X295058Y-38081D01*
X295075Y-38031D01*
X295098Y-37984D01*
X295103Y-37977D01*
X295119Y-37953D01*
X295129Y-37923D01*
X295152Y-37876D01*
X295155Y-37871D01*
X295156Y-37862D01*
X295166Y-37810D01*
X295183Y-37761D01*
X295206Y-37714D01*
X295227Y-37683D01*
X295237Y-37653D01*
X295260Y-37606D01*
X295289Y-37562D01*
X295324Y-37523D01*
X295339Y-37510D01*
X295345Y-37490D01*
X295368Y-37443D01*
X295389Y-37413D01*
X295399Y-37382D01*
X295422Y-37335D01*
X295451Y-37292D01*
X295486Y-37252D01*
X295501Y-37239D01*
X295507Y-37220D01*
X295531Y-37173D01*
X295560Y-37130D01*
X295594Y-37090D01*
X295623Y-37065D01*
X295648Y-37036D01*
X295663Y-37023D01*
X295670Y-37004D01*
X295693Y-36957D01*
X295722Y-36913D01*
X295756Y-36874D01*
X295785Y-36849D01*
X295810Y-36820D01*
X295839Y-36794D01*
X295865Y-36766D01*
X295893Y-36740D01*
X295919Y-36712D01*
X295947Y-36686D01*
X295973Y-36658D01*
X296002Y-36632D01*
X296027Y-36604D01*
X296056Y-36578D01*
X296081Y-36549D01*
X296110Y-36524D01*
X296135Y-36495D01*
X296174Y-36461D01*
X296218Y-36432D01*
X296265Y-36408D01*
X296284Y-36402D01*
X296297Y-36387D01*
X296326Y-36362D01*
X296351Y-36333D01*
X296380Y-36308D01*
X296405Y-36279D01*
X296445Y-36245D01*
X296488Y-36215D01*
X296535Y-36192D01*
X296554Y-36186D01*
X296567Y-36171D01*
X296607Y-36136D01*
X296650Y-36107D01*
X296697Y-36084D01*
X296728Y-36074D01*
X296758Y-36053D01*
X296806Y-36030D01*
X296825Y-36024D01*
X296838Y-36009D01*
X296877Y-35974D01*
X296921Y-35945D01*
X296968Y-35922D01*
X296998Y-35912D01*
X297029Y-35891D01*
X297076Y-35868D01*
X297125Y-35851D01*
X297177Y-35841D01*
X297186Y-35840D01*
X297191Y-35837D01*
X297238Y-35814D01*
X297268Y-35804D01*
X297299Y-35783D01*
X297346Y-35760D01*
X297396Y-35743D01*
X297447Y-35733D01*
X297457Y-35732D01*
X297461Y-35729D01*
X297508Y-35706D01*
X297558Y-35689D01*
X297609Y-35679D01*
X297619Y-35678D01*
X297623Y-35675D01*
X297671Y-35652D01*
X297720Y-35635D01*
X297772Y-35625D01*
X297824Y-35621D01*
X297839D01*
X297840Y-35621D01*
X297887Y-35598D01*
X297936Y-35581D01*
X297988Y-35570D01*
X298040Y-35567D01*
X298164D01*
X298164Y-35567D01*
X298211Y-35544D01*
X298261Y-35527D01*
X298312Y-35516D01*
X298364Y-35513D01*
X299338D01*
X299390Y-35516D01*
D02*
G37*
G36*
X393404Y-44491D02*
X393455Y-44501D01*
X393505Y-44518D01*
X393552Y-44541D01*
X393552Y-44541D01*
X393622D01*
X393674Y-44545D01*
X393725Y-44555D01*
X393775Y-44572D01*
X393822Y-44595D01*
X393827Y-44598D01*
X393836Y-44599D01*
X393888Y-44609D01*
X393937Y-44626D01*
X393984Y-44649D01*
X393989Y-44652D01*
X393999Y-44653D01*
X394050Y-44663D01*
X394099Y-44680D01*
X394147Y-44703D01*
X394177Y-44724D01*
X394208Y-44734D01*
X394255Y-44757D01*
X394298Y-44786D01*
X394338Y-44821D01*
X394351Y-44836D01*
X394370Y-44842D01*
X394417Y-44865D01*
X394448Y-44886D01*
X394478Y-44896D01*
X394525Y-44919D01*
X394569Y-44949D01*
X394608Y-44983D01*
X394633Y-45012D01*
X394662Y-45037D01*
X394687Y-45066D01*
X394716Y-45091D01*
X394741Y-45120D01*
X394770Y-45145D01*
X394795Y-45174D01*
X394824Y-45199D01*
X394849Y-45228D01*
X394878Y-45254D01*
X394903Y-45282D01*
X394932Y-45307D01*
X394958Y-45336D01*
X394987Y-45362D01*
X395012Y-45390D01*
X395040Y-45416D01*
X395075Y-45455D01*
X395104Y-45499D01*
X395127Y-45546D01*
X395134Y-45565D01*
X395149Y-45578D01*
X395183Y-45617D01*
X395212Y-45661D01*
X395235Y-45708D01*
X395246Y-45738D01*
X395266Y-45769D01*
X395290Y-45816D01*
X395300Y-45846D01*
X395321Y-45877D01*
X395344Y-45924D01*
X395360Y-45974D01*
X395371Y-46025D01*
X395371Y-46035D01*
X395374Y-46039D01*
X395398Y-46086D01*
X395415Y-46136D01*
X395425Y-46187D01*
X395425Y-46197D01*
X395429Y-46202D01*
X395452Y-46248D01*
X395469Y-46298D01*
X395479Y-46350D01*
X395482Y-46402D01*
Y-46456D01*
Y-46471D01*
X395483Y-46472D01*
X395506Y-46519D01*
X395523Y-46569D01*
X395533Y-46620D01*
X395536Y-46672D01*
Y-46726D01*
Y-46780D01*
Y-46834D01*
Y-46889D01*
Y-46942D01*
Y-46997D01*
Y-47051D01*
Y-47105D01*
Y-47159D01*
Y-47213D01*
X395533Y-47265D01*
X395523Y-47317D01*
X395506Y-47366D01*
X395483Y-47413D01*
X395482Y-47414D01*
Y-47429D01*
Y-47483D01*
X395479Y-47535D01*
X395469Y-47587D01*
X395452Y-47637D01*
X395429Y-47684D01*
X395425Y-47688D01*
X395425Y-47698D01*
X395415Y-47749D01*
X395398Y-47799D01*
X395374Y-47846D01*
X395354Y-47877D01*
X395344Y-47907D01*
X395321Y-47954D01*
X395300Y-47985D01*
X395292Y-48008D01*
X395290Y-48015D01*
X395266Y-48062D01*
X395246Y-48093D01*
X395240Y-48109D01*
X395235Y-48123D01*
X395212Y-48170D01*
X395192Y-48201D01*
X395181Y-48231D01*
X395158Y-48278D01*
X395129Y-48322D01*
X395095Y-48361D01*
X395070Y-48383D01*
X395066Y-48386D01*
X395040Y-48415D01*
X395026Y-48428D01*
X395019Y-48447D01*
X394996Y-48494D01*
X394967Y-48538D01*
X394932Y-48577D01*
X394903Y-48603D01*
X394878Y-48632D01*
X394850Y-48657D01*
X394824Y-48686D01*
X394795Y-48711D01*
X394770Y-48740D01*
X394731Y-48774D01*
X394687Y-48803D01*
X394640Y-48827D01*
X394621Y-48833D01*
X394608Y-48848D01*
X394579Y-48873D01*
X394554Y-48902D01*
X394514Y-48937D01*
X394471Y-48966D01*
X394424Y-48989D01*
X394394Y-48999D01*
X394363Y-49020D01*
X394316Y-49043D01*
X394297Y-49049D01*
X394284Y-49064D01*
X394244Y-49099D01*
X394201Y-49128D01*
X394154Y-49151D01*
X394104Y-49168D01*
X394053Y-49178D01*
X394043Y-49179D01*
D01*
X394038Y-49182D01*
X393991Y-49205D01*
X393942Y-49222D01*
X393890Y-49232D01*
X393881Y-49233D01*
X393876Y-49236D01*
X393829Y-49259D01*
X393780Y-49276D01*
X393728Y-49286D01*
X393719Y-49287D01*
X393714Y-49290D01*
X393667Y-49313D01*
X393617Y-49330D01*
X393566Y-49340D01*
X393514Y-49344D01*
X392703D01*
X392650Y-49340D01*
X392599Y-49330D01*
X392549Y-49313D01*
X392502Y-49290D01*
X392502Y-49290D01*
X392487D01*
X392434Y-49286D01*
X392383Y-49276D01*
X392333Y-49259D01*
X392286Y-49236D01*
X392255Y-49215D01*
X392225Y-49205D01*
X392178Y-49182D01*
X392173Y-49179D01*
X392164Y-49178D01*
X392112Y-49168D01*
X392063Y-49151D01*
X392016Y-49128D01*
X391985Y-49107D01*
X391955Y-49097D01*
X391908Y-49074D01*
X391864Y-49045D01*
X391825Y-49010D01*
X391812Y-48995D01*
X391792Y-48989D01*
X391745Y-48966D01*
X391702Y-48937D01*
X391662Y-48902D01*
X391650Y-48887D01*
X391630Y-48881D01*
X391583Y-48858D01*
X391540Y-48828D01*
X391500Y-48794D01*
X391475Y-48765D01*
X391446Y-48740D01*
X391421Y-48711D01*
X391392Y-48686D01*
X391367Y-48657D01*
X391338Y-48632D01*
X391313Y-48603D01*
X391284Y-48577D01*
X391259Y-48549D01*
X391230Y-48524D01*
X391195Y-48484D01*
X391166Y-48440D01*
X391143Y-48393D01*
X391140Y-48385D01*
X391137Y-48374D01*
X391122Y-48361D01*
X391087Y-48322D01*
X391058Y-48278D01*
X391035Y-48231D01*
X391028Y-48212D01*
X391014Y-48199D01*
X390979Y-48160D01*
X390950Y-48116D01*
X390927Y-48069D01*
X390921Y-48052D01*
X390916Y-48039D01*
X390896Y-48008D01*
X390873Y-47961D01*
X390856Y-47911D01*
X390846Y-47860D01*
X390845Y-47850D01*
X390842Y-47846D01*
X390819Y-47799D01*
X390802Y-47749D01*
X390792Y-47698D01*
X390791Y-47688D01*
X390788Y-47684D01*
X390765Y-47637D01*
X390748Y-47587D01*
X390738Y-47535D01*
X390734Y-47483D01*
Y-47468D01*
X390734Y-47467D01*
X390710Y-47420D01*
X390694Y-47371D01*
X390683Y-47319D01*
X390680Y-47267D01*
Y-47213D01*
Y-47159D01*
Y-47105D01*
Y-47051D01*
Y-46997D01*
Y-46942D01*
Y-46889D01*
Y-46834D01*
Y-46780D01*
Y-46726D01*
Y-46672D01*
Y-46618D01*
Y-46564D01*
X390683Y-46512D01*
X390694Y-46460D01*
X390710Y-46411D01*
X390734Y-46364D01*
X390734Y-46363D01*
Y-46348D01*
X390738Y-46295D01*
X390748Y-46244D01*
X390765Y-46194D01*
X390788Y-46147D01*
X390791Y-46143D01*
X390792Y-46133D01*
X390802Y-46082D01*
X390819Y-46032D01*
X390842Y-45985D01*
X390852Y-45969D01*
X390862Y-45954D01*
X390873Y-45924D01*
X390896Y-45877D01*
X390916Y-45846D01*
X390927Y-45816D01*
X390950Y-45769D01*
X390970Y-45738D01*
X390981Y-45708D01*
X391004Y-45661D01*
X391033Y-45617D01*
X391068Y-45578D01*
X391082Y-45565D01*
X391089Y-45546D01*
X391112Y-45499D01*
X391141Y-45455D01*
X391176Y-45416D01*
X391205Y-45390D01*
X391230Y-45362D01*
X391259Y-45336D01*
X391284Y-45307D01*
X391313Y-45282D01*
X391338Y-45254D01*
X391367Y-45228D01*
X391392Y-45199D01*
X391421Y-45174D01*
X391446Y-45145D01*
X391475Y-45120D01*
X391500Y-45091D01*
X391529Y-45066D01*
X391554Y-45037D01*
X391583Y-45012D01*
X391608Y-44983D01*
X391648Y-44949D01*
X391691Y-44919D01*
X391738Y-44896D01*
X391758Y-44890D01*
X391771Y-44875D01*
X391810Y-44840D01*
X391853Y-44811D01*
X391901Y-44788D01*
X391931Y-44778D01*
X391962Y-44757D01*
X392009Y-44734D01*
X392039Y-44724D01*
X392070Y-44703D01*
X392117Y-44680D01*
X392166Y-44663D01*
X392218Y-44653D01*
X392227Y-44652D01*
X392232Y-44649D01*
X392279Y-44626D01*
X392329Y-44609D01*
X392380Y-44599D01*
X392389Y-44598D01*
X392394Y-44595D01*
X392441Y-44572D01*
X392491Y-44555D01*
X392542Y-44545D01*
X392595Y-44541D01*
X392664D01*
X392665Y-44541D01*
X392711Y-44518D01*
X392761Y-44501D01*
X392813Y-44491D01*
X392865Y-44487D01*
X393352D01*
X393404Y-44491D01*
D02*
G37*
G36*
X393620Y-51843D02*
X393671Y-51853D01*
X393721Y-51870D01*
X393768Y-51894D01*
X393773Y-51897D01*
X393782Y-51897D01*
X393834Y-51907D01*
X393883Y-51924D01*
X393930Y-51947D01*
X393935Y-51951D01*
X393944Y-51951D01*
X393996Y-51961D01*
X394045Y-51978D01*
X394092Y-52002D01*
X394123Y-52022D01*
X394154Y-52032D01*
X394201Y-52056D01*
X394231Y-52076D01*
X394262Y-52087D01*
X394309Y-52110D01*
X394340Y-52130D01*
X394370Y-52141D01*
X394417Y-52164D01*
X394461Y-52193D01*
X394500Y-52227D01*
X394513Y-52242D01*
X394532Y-52249D01*
X394579Y-52272D01*
X394623Y-52301D01*
X394662Y-52336D01*
X394687Y-52364D01*
X394716Y-52390D01*
X394741Y-52419D01*
X394770Y-52444D01*
X394795Y-52473D01*
X394824Y-52498D01*
X394849Y-52527D01*
X394878Y-52552D01*
X394903Y-52581D01*
X394932Y-52606D01*
X394958Y-52635D01*
X394987Y-52660D01*
X395021Y-52699D01*
X395050Y-52743D01*
X395073Y-52790D01*
X395080Y-52809D01*
X395095Y-52822D01*
X395129Y-52862D01*
X395158Y-52905D01*
X395181Y-52952D01*
X395192Y-52982D01*
X395212Y-53013D01*
X395235Y-53060D01*
X395246Y-53091D01*
X395266Y-53121D01*
X395290Y-53168D01*
X395300Y-53199D01*
X395321Y-53229D01*
X395344Y-53277D01*
X395354Y-53307D01*
X395374Y-53338D01*
X395398Y-53385D01*
X395415Y-53434D01*
X395425Y-53486D01*
X395425Y-53495D01*
X395429Y-53500D01*
X395452Y-53547D01*
X395469Y-53597D01*
X395479Y-53648D01*
X395482Y-53700D01*
Y-53754D01*
Y-53770D01*
X395483Y-53770D01*
X395506Y-53817D01*
X395523Y-53867D01*
X395533Y-53918D01*
X395536Y-53971D01*
Y-54025D01*
Y-54079D01*
Y-54133D01*
Y-54187D01*
Y-54241D01*
Y-54295D01*
Y-54349D01*
Y-54403D01*
Y-54457D01*
Y-54511D01*
X395533Y-54563D01*
X395523Y-54615D01*
X395506Y-54665D01*
X395483Y-54712D01*
X395482Y-54712D01*
Y-54728D01*
Y-54782D01*
X395479Y-54834D01*
X395469Y-54885D01*
X395452Y-54935D01*
X395429Y-54982D01*
X395425Y-54987D01*
X395425Y-54996D01*
X395415Y-55048D01*
X395398Y-55097D01*
X395374Y-55144D01*
X395354Y-55175D01*
X395344Y-55205D01*
X395321Y-55252D01*
X395300Y-55283D01*
X395290Y-55313D01*
X395266Y-55360D01*
X395246Y-55391D01*
X395246Y-55392D01*
X395235Y-55422D01*
X395212Y-55468D01*
X395192Y-55499D01*
X395181Y-55530D01*
X395158Y-55577D01*
X395129Y-55620D01*
X395095Y-55660D01*
X395080Y-55673D01*
X395073Y-55692D01*
X395050Y-55739D01*
X395021Y-55782D01*
X394987Y-55822D01*
X394958Y-55847D01*
X394932Y-55876D01*
X394903Y-55901D01*
X394878Y-55930D01*
X394850Y-55955D01*
X394828Y-55980D01*
X394824Y-55984D01*
X394795Y-56009D01*
X394770Y-56038D01*
X394741Y-56063D01*
X394716Y-56092D01*
X394677Y-56127D01*
X394633Y-56156D01*
X394586Y-56179D01*
X394567Y-56186D01*
X394554Y-56200D01*
X394525Y-56226D01*
X394500Y-56254D01*
X394461Y-56289D01*
X394417Y-56318D01*
X394370Y-56341D01*
X394340Y-56352D01*
X394309Y-56372D01*
X394262Y-56395D01*
X394231Y-56406D01*
X394201Y-56426D01*
X394154Y-56449D01*
X394123Y-56460D01*
X394092Y-56480D01*
X394045Y-56503D01*
X393996Y-56520D01*
X393944Y-56530D01*
X393935Y-56531D01*
X393930Y-56534D01*
X393883Y-56558D01*
X393834Y-56574D01*
X393782Y-56585D01*
X393773Y-56585D01*
X393768Y-56588D01*
X393721Y-56612D01*
X393671Y-56628D01*
X393620Y-56639D01*
X393568Y-56642D01*
X392649D01*
X392596Y-56639D01*
X392545Y-56628D01*
X392495Y-56612D01*
X392448Y-56588D01*
X392443Y-56585D01*
X392434Y-56585D01*
X392383Y-56574D01*
X392333Y-56558D01*
X392286Y-56534D01*
X392281Y-56531D01*
X392272Y-56530D01*
X392220Y-56520D01*
X392171Y-56503D01*
X392124Y-56480D01*
X392093Y-56460D01*
X392063Y-56449D01*
X392016Y-56426D01*
X391985Y-56406D01*
X391955Y-56395D01*
X391908Y-56372D01*
X391877Y-56352D01*
X391846Y-56341D01*
X391799Y-56318D01*
X391756Y-56289D01*
X391716Y-56254D01*
X391704Y-56240D01*
X391684Y-56233D01*
X391637Y-56210D01*
X391594Y-56181D01*
X391554Y-56146D01*
X391529Y-56117D01*
X391500Y-56092D01*
X391475Y-56063D01*
X391446Y-56038D01*
X391421Y-56009D01*
X391392Y-55984D01*
X391367Y-55955D01*
X391338Y-55930D01*
X391313Y-55901D01*
X391284Y-55876D01*
X391259Y-55847D01*
X391230Y-55822D01*
X391205Y-55793D01*
X391176Y-55768D01*
X391141Y-55728D01*
X391112Y-55685D01*
X391089Y-55638D01*
X391082Y-55619D01*
X391068Y-55606D01*
X391033Y-55566D01*
X391004Y-55523D01*
X390981Y-55475D01*
X390970Y-55445D01*
X390950Y-55414D01*
X390927Y-55367D01*
X390924Y-55360D01*
X390916Y-55337D01*
X390896Y-55306D01*
X390873Y-55259D01*
X390862Y-55229D01*
X390842Y-55198D01*
X390819Y-55151D01*
X390802Y-55102D01*
X390792Y-55050D01*
X390791Y-55041D01*
X390788Y-55036D01*
X390765Y-54989D01*
X390748Y-54939D01*
X390738Y-54888D01*
X390734Y-54836D01*
Y-54782D01*
Y-54766D01*
X390734Y-54766D01*
X390710Y-54719D01*
X390694Y-54669D01*
X390683Y-54618D01*
X390680Y-54565D01*
Y-54511D01*
Y-54457D01*
Y-54403D01*
Y-54349D01*
Y-54295D01*
Y-54241D01*
Y-54187D01*
Y-54133D01*
Y-54079D01*
Y-54025D01*
Y-53971D01*
Y-53917D01*
X390683Y-53864D01*
X390694Y-53813D01*
X390710Y-53763D01*
X390734Y-53716D01*
X390734Y-53716D01*
Y-53700D01*
Y-53646D01*
X390738Y-53594D01*
X390748Y-53543D01*
X390765Y-53493D01*
X390788Y-53446D01*
X390791Y-53441D01*
X390792Y-53432D01*
X390802Y-53380D01*
X390819Y-53331D01*
X390842Y-53284D01*
X390862Y-53253D01*
X390873Y-53223D01*
X390896Y-53175D01*
X390916Y-53145D01*
X390927Y-53114D01*
X390950Y-53067D01*
X390955Y-53060D01*
X390970Y-53037D01*
X390981Y-53006D01*
X391004Y-52959D01*
X391033Y-52916D01*
X391068Y-52876D01*
X391082Y-52863D01*
X391089Y-52844D01*
X391112Y-52797D01*
X391141Y-52753D01*
X391176Y-52714D01*
X391205Y-52689D01*
X391230Y-52660D01*
X391259Y-52635D01*
X391284Y-52606D01*
X391313Y-52581D01*
X391338Y-52552D01*
X391367Y-52527D01*
X391392Y-52498D01*
X391421Y-52473D01*
X391446Y-52444D01*
X391475Y-52419D01*
X391500Y-52390D01*
X391529Y-52364D01*
X391554Y-52336D01*
X391594Y-52301D01*
X391637Y-52272D01*
X391684Y-52249D01*
X391704Y-52242D01*
X391716Y-52227D01*
X391756Y-52193D01*
X391799Y-52164D01*
X391846Y-52141D01*
X391877Y-52130D01*
X391908Y-52110D01*
X391955Y-52087D01*
X391985Y-52076D01*
X392016Y-52056D01*
X392063Y-52032D01*
X392093Y-52022D01*
X392124Y-52002D01*
X392171Y-51978D01*
X392201Y-51968D01*
X392232Y-51947D01*
X392279Y-51924D01*
X392329Y-51907D01*
X392380Y-51897D01*
X392432Y-51894D01*
X392448D01*
X392448Y-51894D01*
X392495Y-51870D01*
X392545Y-51853D01*
X392596Y-51843D01*
X392649Y-51840D01*
X393568D01*
X393620Y-51843D01*
D02*
G37*
G36*
X407460Y-7296D02*
X407511Y-7306D01*
X407561Y-7323D01*
X407608Y-7346D01*
X407652Y-7376D01*
X407691Y-7410D01*
X407726Y-7450D01*
X407755Y-7493D01*
X407778Y-7540D01*
X407795Y-7590D01*
X407805Y-7641D01*
X407808Y-7694D01*
Y-7748D01*
Y-7802D01*
Y-7856D01*
Y-7910D01*
Y-7964D01*
Y-8018D01*
Y-8072D01*
Y-8126D01*
Y-8180D01*
Y-8234D01*
Y-8288D01*
Y-8342D01*
Y-8396D01*
Y-8450D01*
Y-8504D01*
Y-8558D01*
Y-8613D01*
Y-8667D01*
Y-8721D01*
Y-8775D01*
Y-8829D01*
Y-8883D01*
Y-8937D01*
Y-8991D01*
Y-9045D01*
Y-9099D01*
Y-9153D01*
Y-9207D01*
Y-9261D01*
Y-9315D01*
Y-9369D01*
Y-9424D01*
Y-9478D01*
Y-9532D01*
Y-9586D01*
Y-9640D01*
Y-9694D01*
Y-9748D01*
X407805Y-9800D01*
X407795Y-9852D01*
X407778Y-9901D01*
X407755Y-9948D01*
X407726Y-9992D01*
X407691Y-10031D01*
X407652Y-10066D01*
X407608Y-10095D01*
X407561Y-10118D01*
X407511Y-10135D01*
X407460Y-10145D01*
X407408Y-10149D01*
X400743D01*
X400742Y-10149D01*
X400695Y-10172D01*
X400645Y-10189D01*
X400594Y-10199D01*
X400542Y-10203D01*
X400526D01*
X400526Y-10203D01*
X400479Y-10226D01*
X400449Y-10237D01*
X400445Y-10239D01*
X400418Y-10257D01*
X400371Y-10280D01*
X400340Y-10291D01*
X400310Y-10311D01*
X400263Y-10334D01*
X400243Y-10341D01*
X400231Y-10356D01*
X400191Y-10390D01*
X400147Y-10419D01*
X400100Y-10443D01*
X400081Y-10449D01*
X400068Y-10464D01*
X400054Y-10477D01*
X400047Y-10496D01*
X400024Y-10543D01*
X399995Y-10587D01*
X399960Y-10626D01*
X399945Y-10639D01*
X399939Y-10658D01*
X399916Y-10705D01*
X399895Y-10736D01*
X399885Y-10766D01*
X399862Y-10813D01*
X399841Y-10844D01*
X399837Y-10856D01*
X399831Y-10874D01*
X399808Y-10921D01*
X399807Y-10922D01*
Y-10937D01*
Y-10991D01*
X399804Y-11044D01*
X399794Y-11095D01*
X399777Y-11145D01*
X399753Y-11192D01*
X399753Y-11192D01*
Y-11208D01*
Y-11262D01*
Y-11316D01*
Y-11370D01*
Y-11424D01*
Y-11478D01*
Y-11532D01*
Y-11586D01*
Y-11640D01*
Y-11694D01*
Y-11748D01*
Y-11802D01*
Y-11856D01*
Y-11910D01*
Y-11964D01*
Y-12019D01*
Y-12072D01*
Y-12127D01*
Y-12181D01*
Y-12235D01*
Y-12289D01*
Y-12343D01*
Y-12397D01*
Y-12451D01*
Y-12505D01*
Y-12559D01*
Y-12613D01*
Y-12667D01*
Y-12721D01*
Y-12775D01*
Y-12829D01*
Y-12883D01*
Y-12937D01*
Y-12992D01*
Y-13046D01*
Y-13100D01*
Y-13154D01*
Y-13208D01*
Y-13262D01*
Y-13316D01*
Y-13370D01*
Y-13424D01*
Y-13478D01*
Y-13532D01*
Y-13586D01*
Y-13640D01*
Y-13694D01*
Y-13748D01*
Y-13803D01*
Y-13857D01*
Y-13911D01*
Y-13965D01*
Y-14019D01*
Y-14073D01*
Y-14127D01*
Y-14181D01*
Y-14235D01*
Y-14289D01*
Y-14343D01*
Y-14397D01*
Y-14451D01*
Y-14505D01*
Y-14559D01*
Y-14614D01*
Y-14668D01*
Y-14722D01*
Y-14776D01*
Y-14830D01*
Y-14884D01*
Y-14938D01*
Y-14992D01*
Y-15046D01*
Y-15100D01*
Y-15154D01*
Y-15208D01*
Y-15262D01*
Y-15316D01*
Y-15370D01*
Y-15424D01*
Y-15478D01*
Y-15532D01*
Y-15587D01*
Y-15641D01*
Y-15695D01*
Y-15749D01*
Y-15803D01*
Y-15857D01*
Y-15911D01*
Y-15965D01*
Y-16019D01*
Y-16073D01*
Y-16127D01*
Y-16181D01*
Y-16235D01*
Y-16289D01*
Y-16343D01*
Y-16398D01*
Y-16452D01*
Y-16506D01*
Y-16560D01*
Y-16614D01*
Y-16668D01*
Y-16722D01*
Y-16776D01*
Y-16830D01*
Y-16884D01*
Y-16938D01*
Y-16992D01*
Y-17046D01*
Y-17100D01*
Y-17154D01*
Y-17208D01*
Y-17263D01*
Y-17317D01*
Y-17371D01*
Y-17425D01*
Y-17479D01*
Y-17533D01*
Y-17587D01*
Y-17641D01*
Y-17695D01*
Y-17749D01*
Y-17803D01*
Y-17857D01*
Y-17911D01*
Y-17965D01*
Y-18019D01*
Y-18073D01*
Y-18127D01*
Y-18181D01*
Y-18236D01*
Y-18290D01*
Y-18344D01*
Y-18398D01*
Y-18452D01*
Y-18506D01*
Y-18560D01*
Y-18614D01*
Y-18668D01*
Y-18722D01*
Y-18776D01*
Y-18830D01*
Y-18884D01*
Y-18938D01*
Y-18993D01*
Y-19047D01*
Y-19101D01*
Y-19155D01*
Y-19209D01*
Y-19263D01*
Y-19317D01*
Y-19371D01*
Y-19425D01*
Y-19479D01*
Y-19533D01*
Y-19587D01*
Y-19641D01*
Y-19695D01*
Y-19749D01*
Y-19803D01*
Y-19858D01*
Y-19911D01*
Y-19966D01*
Y-20020D01*
Y-20074D01*
Y-20128D01*
Y-20182D01*
Y-20236D01*
Y-20290D01*
Y-20344D01*
Y-20398D01*
Y-20452D01*
Y-20506D01*
Y-20560D01*
Y-20614D01*
Y-20668D01*
Y-20722D01*
Y-20776D01*
Y-20831D01*
Y-20885D01*
Y-20939D01*
Y-20993D01*
Y-21047D01*
Y-21101D01*
Y-21155D01*
Y-21209D01*
Y-21263D01*
Y-21317D01*
Y-21371D01*
Y-21425D01*
Y-21479D01*
Y-21533D01*
Y-21587D01*
Y-21642D01*
Y-21696D01*
Y-21750D01*
Y-21804D01*
Y-21858D01*
Y-21912D01*
Y-21966D01*
Y-22020D01*
Y-22074D01*
Y-22128D01*
Y-22182D01*
Y-22236D01*
Y-22290D01*
Y-22344D01*
Y-22398D01*
Y-22452D01*
Y-22506D01*
Y-22561D01*
Y-22615D01*
Y-22669D01*
Y-22723D01*
Y-22777D01*
Y-22831D01*
Y-22885D01*
Y-22939D01*
Y-22993D01*
Y-23047D01*
Y-23101D01*
Y-23155D01*
Y-23209D01*
Y-23263D01*
Y-23317D01*
Y-23371D01*
Y-23426D01*
Y-23480D01*
Y-23534D01*
Y-23588D01*
Y-23642D01*
Y-23696D01*
Y-23750D01*
Y-23804D01*
Y-23858D01*
Y-23912D01*
Y-23966D01*
Y-24020D01*
Y-24074D01*
Y-24128D01*
Y-24182D01*
Y-24237D01*
Y-24291D01*
Y-24345D01*
Y-24399D01*
Y-24453D01*
Y-24507D01*
Y-24561D01*
Y-24615D01*
Y-24669D01*
Y-24723D01*
Y-24777D01*
Y-24831D01*
Y-24885D01*
Y-24939D01*
Y-24993D01*
Y-25047D01*
Y-25102D01*
Y-25155D01*
Y-25210D01*
Y-25264D01*
Y-25318D01*
Y-25372D01*
Y-25426D01*
Y-25480D01*
Y-25534D01*
Y-25588D01*
Y-25642D01*
Y-25696D01*
Y-25750D01*
Y-25804D01*
Y-25858D01*
Y-25912D01*
Y-25967D01*
Y-26021D01*
Y-26075D01*
Y-26129D01*
Y-26183D01*
Y-26237D01*
Y-26291D01*
Y-26345D01*
Y-26399D01*
Y-26453D01*
Y-26507D01*
Y-26561D01*
Y-26615D01*
Y-26669D01*
Y-26723D01*
Y-26777D01*
Y-26831D01*
Y-26886D01*
Y-26940D01*
Y-26994D01*
Y-27048D01*
Y-27102D01*
Y-27156D01*
Y-27210D01*
Y-27264D01*
Y-27318D01*
Y-27372D01*
Y-27426D01*
Y-27480D01*
Y-27534D01*
Y-27588D01*
Y-27642D01*
Y-27696D01*
Y-27751D01*
Y-27805D01*
Y-27859D01*
Y-27913D01*
Y-27967D01*
Y-28021D01*
Y-28075D01*
Y-28129D01*
Y-28183D01*
Y-28237D01*
Y-28291D01*
Y-28345D01*
Y-28399D01*
Y-28453D01*
Y-28507D01*
Y-28561D01*
Y-28615D01*
Y-28670D01*
Y-28724D01*
Y-28778D01*
Y-28832D01*
Y-28886D01*
Y-28940D01*
Y-28994D01*
Y-29048D01*
Y-29102D01*
Y-29156D01*
Y-29210D01*
Y-29264D01*
Y-29318D01*
Y-29372D01*
Y-29426D01*
Y-29480D01*
Y-29535D01*
Y-29589D01*
Y-29643D01*
Y-29697D01*
Y-29751D01*
Y-29805D01*
Y-29859D01*
Y-29913D01*
Y-29967D01*
Y-30021D01*
Y-30075D01*
Y-30129D01*
Y-30183D01*
Y-30237D01*
Y-30291D01*
Y-30345D01*
Y-30400D01*
Y-30454D01*
Y-30508D01*
Y-30562D01*
Y-30616D01*
Y-30670D01*
Y-30724D01*
Y-30778D01*
Y-30832D01*
Y-30886D01*
Y-30940D01*
Y-30994D01*
Y-31048D01*
Y-31102D01*
Y-31156D01*
Y-31211D01*
Y-31265D01*
Y-31319D01*
Y-31373D01*
Y-31427D01*
Y-31481D01*
Y-31535D01*
Y-31589D01*
Y-31643D01*
Y-31697D01*
Y-31751D01*
Y-31805D01*
Y-31859D01*
Y-31913D01*
Y-31967D01*
Y-32021D01*
Y-32076D01*
Y-32129D01*
Y-32184D01*
Y-32238D01*
Y-32292D01*
Y-32346D01*
Y-32400D01*
Y-32454D01*
Y-32508D01*
Y-32562D01*
Y-32616D01*
Y-32670D01*
Y-32724D01*
Y-32778D01*
Y-32832D01*
Y-32886D01*
Y-32941D01*
Y-32994D01*
Y-33049D01*
Y-33103D01*
Y-33157D01*
Y-33211D01*
Y-33265D01*
Y-33319D01*
Y-33373D01*
Y-33427D01*
Y-33481D01*
Y-33535D01*
Y-33589D01*
Y-33643D01*
Y-33697D01*
Y-33751D01*
Y-33806D01*
Y-33860D01*
Y-33914D01*
Y-33968D01*
Y-34022D01*
Y-34076D01*
Y-34130D01*
Y-34184D01*
Y-34238D01*
Y-34292D01*
Y-34346D01*
Y-34400D01*
Y-34454D01*
Y-34508D01*
Y-34562D01*
Y-34616D01*
Y-34670D01*
Y-34725D01*
Y-34779D01*
Y-34833D01*
Y-34887D01*
Y-34941D01*
Y-34995D01*
Y-35049D01*
Y-35103D01*
Y-35157D01*
Y-35211D01*
Y-35265D01*
Y-35319D01*
Y-35373D01*
Y-35427D01*
Y-35481D01*
Y-35535D01*
Y-35590D01*
Y-35644D01*
Y-35698D01*
Y-35752D01*
Y-35806D01*
Y-35860D01*
Y-35914D01*
Y-35968D01*
Y-36022D01*
Y-36076D01*
Y-36130D01*
Y-36184D01*
Y-36238D01*
Y-36292D01*
Y-36346D01*
Y-36400D01*
Y-36454D01*
Y-36509D01*
Y-36563D01*
Y-36617D01*
Y-36671D01*
Y-36725D01*
Y-36779D01*
Y-36833D01*
Y-36887D01*
Y-36941D01*
Y-36995D01*
Y-37049D01*
Y-37103D01*
Y-37157D01*
Y-37211D01*
Y-37265D01*
Y-37319D01*
Y-37374D01*
Y-37428D01*
Y-37482D01*
Y-37536D01*
Y-37590D01*
Y-37644D01*
Y-37698D01*
Y-37752D01*
Y-37806D01*
Y-37860D01*
Y-37914D01*
Y-37968D01*
Y-38022D01*
Y-38076D01*
Y-38130D01*
Y-38184D01*
Y-38238D01*
Y-38293D01*
Y-38347D01*
Y-38401D01*
Y-38455D01*
Y-38509D01*
Y-38563D01*
Y-38617D01*
Y-38671D01*
Y-38725D01*
Y-38779D01*
Y-38833D01*
Y-38887D01*
Y-38941D01*
Y-38995D01*
Y-39050D01*
Y-39103D01*
Y-39158D01*
Y-39212D01*
Y-39266D01*
Y-39320D01*
Y-39374D01*
Y-39428D01*
Y-39482D01*
Y-39536D01*
Y-39590D01*
Y-39644D01*
Y-39698D01*
Y-39752D01*
Y-39806D01*
Y-39860D01*
Y-39915D01*
Y-39968D01*
Y-40023D01*
Y-40077D01*
Y-40131D01*
Y-40185D01*
Y-40239D01*
Y-40293D01*
Y-40347D01*
Y-40401D01*
Y-40455D01*
Y-40509D01*
Y-40563D01*
Y-40617D01*
Y-40671D01*
Y-40725D01*
Y-40780D01*
Y-40834D01*
Y-40888D01*
Y-40942D01*
Y-40996D01*
Y-41050D01*
Y-41104D01*
Y-41158D01*
Y-41212D01*
Y-41266D01*
Y-41320D01*
Y-41374D01*
Y-41428D01*
Y-41482D01*
Y-41536D01*
Y-41590D01*
Y-41644D01*
Y-41699D01*
Y-41753D01*
Y-41807D01*
Y-41861D01*
Y-41915D01*
Y-41969D01*
Y-42023D01*
Y-42077D01*
Y-42131D01*
Y-42185D01*
Y-42239D01*
Y-42293D01*
Y-42347D01*
Y-42401D01*
Y-42455D01*
Y-42509D01*
Y-42564D01*
Y-42618D01*
Y-42672D01*
Y-42726D01*
Y-42780D01*
Y-42834D01*
Y-42888D01*
Y-42942D01*
Y-42996D01*
Y-43050D01*
Y-43104D01*
Y-43158D01*
Y-43212D01*
Y-43266D01*
Y-43320D01*
Y-43374D01*
Y-43429D01*
Y-43483D01*
Y-43537D01*
Y-43591D01*
Y-43645D01*
Y-43699D01*
Y-43753D01*
Y-43807D01*
Y-43861D01*
Y-43915D01*
Y-43969D01*
Y-44023D01*
Y-44077D01*
Y-44131D01*
Y-44185D01*
Y-44239D01*
Y-44293D01*
Y-44348D01*
Y-44402D01*
Y-44456D01*
Y-44510D01*
Y-44564D01*
Y-44618D01*
Y-44672D01*
Y-44726D01*
Y-44780D01*
Y-44834D01*
Y-44888D01*
Y-44942D01*
Y-44996D01*
Y-45050D01*
Y-45104D01*
Y-45158D01*
Y-45213D01*
Y-45267D01*
Y-45321D01*
Y-45375D01*
Y-45429D01*
Y-45483D01*
Y-45537D01*
Y-45591D01*
Y-45645D01*
Y-45699D01*
Y-45753D01*
Y-45807D01*
Y-45861D01*
Y-45915D01*
Y-45969D01*
Y-46023D01*
Y-46077D01*
Y-46132D01*
Y-46186D01*
Y-46240D01*
Y-46294D01*
Y-46348D01*
Y-46402D01*
Y-46456D01*
Y-46510D01*
Y-46564D01*
Y-46618D01*
Y-46672D01*
Y-46726D01*
Y-46780D01*
Y-46834D01*
Y-46889D01*
Y-46942D01*
Y-46997D01*
Y-47051D01*
Y-47105D01*
Y-47159D01*
Y-47213D01*
Y-47267D01*
Y-47321D01*
Y-47375D01*
Y-47429D01*
Y-47483D01*
Y-47537D01*
Y-47591D01*
Y-47645D01*
Y-47699D01*
Y-47754D01*
Y-47807D01*
Y-47862D01*
Y-47916D01*
Y-47970D01*
Y-48024D01*
Y-48078D01*
Y-48132D01*
Y-48186D01*
Y-48240D01*
Y-48294D01*
Y-48348D01*
Y-48402D01*
Y-48456D01*
Y-48510D01*
Y-48564D01*
Y-48619D01*
Y-48673D01*
Y-48727D01*
Y-48781D01*
Y-48835D01*
Y-48889D01*
Y-48943D01*
Y-48997D01*
Y-49051D01*
Y-49105D01*
Y-49159D01*
Y-49213D01*
Y-49267D01*
Y-49321D01*
Y-49375D01*
Y-49429D01*
Y-49483D01*
Y-49538D01*
Y-49592D01*
Y-49646D01*
Y-49700D01*
Y-49754D01*
Y-49808D01*
Y-49862D01*
Y-49916D01*
Y-49970D01*
Y-50024D01*
Y-50078D01*
Y-50132D01*
Y-50186D01*
Y-50240D01*
Y-50294D01*
Y-50348D01*
Y-50402D01*
Y-50457D01*
Y-50511D01*
Y-50565D01*
Y-50619D01*
Y-50673D01*
Y-50727D01*
Y-50781D01*
Y-50835D01*
Y-50889D01*
Y-50943D01*
Y-50997D01*
Y-51051D01*
Y-51105D01*
Y-51159D01*
Y-51213D01*
Y-51267D01*
Y-51322D01*
Y-51376D01*
Y-51430D01*
Y-51484D01*
Y-51538D01*
Y-51592D01*
Y-51646D01*
Y-51700D01*
Y-51754D01*
Y-51808D01*
Y-51862D01*
Y-51916D01*
Y-51970D01*
Y-52024D01*
Y-52078D01*
Y-52132D01*
Y-52187D01*
Y-52241D01*
Y-52295D01*
Y-52349D01*
Y-52403D01*
Y-52457D01*
Y-52511D01*
Y-52565D01*
Y-52619D01*
Y-52673D01*
Y-52727D01*
Y-52781D01*
Y-52835D01*
Y-52889D01*
Y-52943D01*
Y-52997D01*
Y-53052D01*
Y-53106D01*
Y-53160D01*
Y-53214D01*
Y-53268D01*
Y-53322D01*
Y-53376D01*
Y-53430D01*
Y-53484D01*
Y-53538D01*
Y-53592D01*
Y-53646D01*
Y-53700D01*
Y-53754D01*
Y-53808D01*
Y-53863D01*
Y-53917D01*
Y-53971D01*
Y-54025D01*
Y-54079D01*
Y-54133D01*
Y-54187D01*
Y-54241D01*
Y-54295D01*
Y-54349D01*
Y-54403D01*
Y-54457D01*
Y-54511D01*
Y-54565D01*
Y-54619D01*
Y-54673D01*
Y-54728D01*
Y-54782D01*
Y-54836D01*
Y-54890D01*
Y-54944D01*
Y-54998D01*
Y-55052D01*
Y-55106D01*
Y-55160D01*
Y-55214D01*
Y-55268D01*
Y-55322D01*
Y-55376D01*
Y-55430D01*
Y-55484D01*
Y-55538D01*
Y-55592D01*
Y-55647D01*
Y-55701D01*
Y-55755D01*
Y-55809D01*
Y-55863D01*
Y-55917D01*
Y-55971D01*
Y-56025D01*
Y-56079D01*
Y-56133D01*
Y-56187D01*
Y-56241D01*
Y-56295D01*
Y-56349D01*
Y-56403D01*
Y-56457D01*
Y-56511D01*
Y-56566D01*
Y-56620D01*
Y-56674D01*
Y-56728D01*
Y-56782D01*
Y-56836D01*
Y-56890D01*
Y-56944D01*
Y-56998D01*
Y-57052D01*
Y-57106D01*
Y-57160D01*
Y-57214D01*
Y-57268D01*
Y-57322D01*
Y-57376D01*
Y-57431D01*
Y-57485D01*
Y-57539D01*
Y-57593D01*
Y-57647D01*
Y-57701D01*
Y-57755D01*
Y-57809D01*
Y-57863D01*
Y-57917D01*
Y-57971D01*
Y-58025D01*
Y-58079D01*
Y-58133D01*
Y-58187D01*
Y-58241D01*
Y-58296D01*
Y-58350D01*
Y-58404D01*
Y-58458D01*
Y-58512D01*
Y-58566D01*
Y-58620D01*
Y-58674D01*
Y-58728D01*
Y-58782D01*
Y-58836D01*
Y-58890D01*
Y-58944D01*
Y-58998D01*
Y-59052D01*
Y-59106D01*
Y-59161D01*
Y-59215D01*
Y-59269D01*
Y-59323D01*
Y-59377D01*
Y-59431D01*
Y-59485D01*
Y-59539D01*
Y-59593D01*
Y-59647D01*
Y-59701D01*
Y-59755D01*
Y-59809D01*
Y-59863D01*
Y-59917D01*
Y-59971D01*
Y-60026D01*
Y-60080D01*
Y-60134D01*
Y-60188D01*
Y-60242D01*
Y-60296D01*
Y-60350D01*
Y-60404D01*
Y-60458D01*
Y-60512D01*
Y-60566D01*
Y-60620D01*
Y-60674D01*
Y-60728D01*
Y-60782D01*
Y-60836D01*
Y-60891D01*
Y-60945D01*
Y-60999D01*
Y-61053D01*
Y-61107D01*
Y-61161D01*
Y-61215D01*
Y-61269D01*
Y-61323D01*
Y-61377D01*
Y-61431D01*
Y-61485D01*
Y-61539D01*
Y-61593D01*
Y-61647D01*
Y-61702D01*
Y-61756D01*
Y-61810D01*
Y-61864D01*
Y-61918D01*
Y-61972D01*
Y-62026D01*
Y-62080D01*
Y-62134D01*
Y-62188D01*
Y-62242D01*
Y-62296D01*
Y-62350D01*
Y-62404D01*
Y-62458D01*
Y-62512D01*
Y-62566D01*
Y-62621D01*
Y-62675D01*
Y-62729D01*
Y-62783D01*
Y-62837D01*
Y-62891D01*
Y-62945D01*
Y-62999D01*
Y-63053D01*
Y-63107D01*
Y-63161D01*
Y-63215D01*
Y-63269D01*
Y-63323D01*
Y-63377D01*
Y-63431D01*
Y-63485D01*
Y-63540D01*
Y-63594D01*
Y-63648D01*
Y-63702D01*
Y-63756D01*
Y-63810D01*
Y-63864D01*
Y-63918D01*
Y-63972D01*
Y-64026D01*
Y-64080D01*
Y-64134D01*
Y-64188D01*
Y-64242D01*
Y-64296D01*
Y-64350D01*
Y-64405D01*
Y-64459D01*
Y-64513D01*
Y-64567D01*
Y-64621D01*
Y-64675D01*
Y-64729D01*
Y-64783D01*
Y-64837D01*
Y-64891D01*
Y-64945D01*
Y-64999D01*
Y-65053D01*
Y-65107D01*
Y-65161D01*
Y-65215D01*
Y-65270D01*
Y-65324D01*
Y-65378D01*
Y-65432D01*
Y-65486D01*
Y-65540D01*
Y-65594D01*
Y-65648D01*
Y-65702D01*
Y-65756D01*
Y-65810D01*
Y-65864D01*
Y-65918D01*
Y-65972D01*
Y-66026D01*
Y-66080D01*
Y-66135D01*
Y-66189D01*
Y-66243D01*
Y-66297D01*
Y-66351D01*
Y-66405D01*
Y-66459D01*
Y-66513D01*
Y-66567D01*
Y-66621D01*
Y-66675D01*
Y-66729D01*
Y-66783D01*
Y-66837D01*
Y-66891D01*
Y-66945D01*
Y-67000D01*
Y-67054D01*
Y-67108D01*
Y-67162D01*
Y-67216D01*
Y-67270D01*
Y-67324D01*
Y-67378D01*
Y-67432D01*
Y-67486D01*
Y-67540D01*
Y-67594D01*
Y-67648D01*
Y-67702D01*
Y-67756D01*
Y-67810D01*
Y-67865D01*
Y-67919D01*
Y-67973D01*
Y-68027D01*
Y-68081D01*
Y-68135D01*
Y-68189D01*
Y-68243D01*
Y-68297D01*
Y-68351D01*
Y-68405D01*
Y-68459D01*
Y-68513D01*
Y-68567D01*
Y-68621D01*
Y-68676D01*
Y-68730D01*
Y-68784D01*
Y-68838D01*
Y-68892D01*
Y-68946D01*
Y-69000D01*
Y-69054D01*
Y-69108D01*
Y-69162D01*
Y-69216D01*
Y-69270D01*
Y-69324D01*
Y-69378D01*
Y-69432D01*
Y-69486D01*
X399750Y-69539D01*
X399740Y-69590D01*
X399723Y-69640D01*
X399699Y-69687D01*
X399670Y-69730D01*
X399636Y-69770D01*
X399596Y-69804D01*
X399553Y-69833D01*
X399506Y-69857D01*
X399456Y-69874D01*
X399405Y-69884D01*
X399352Y-69887D01*
X397352D01*
X397300Y-69884D01*
X397248Y-69874D01*
X397199Y-69857D01*
X397152Y-69833D01*
X397108Y-69804D01*
X397069Y-69770D01*
X397034Y-69730D01*
X397005Y-69687D01*
X396982Y-69640D01*
X396965Y-69590D01*
X396955Y-69539D01*
X396951Y-69486D01*
Y-69432D01*
Y-69378D01*
Y-69324D01*
Y-69270D01*
Y-69216D01*
Y-69162D01*
Y-69108D01*
Y-69054D01*
Y-69000D01*
Y-68946D01*
Y-68892D01*
Y-68838D01*
Y-68784D01*
Y-68730D01*
Y-68676D01*
Y-68621D01*
Y-68567D01*
Y-68513D01*
Y-68459D01*
Y-68405D01*
Y-68351D01*
Y-68297D01*
Y-68243D01*
Y-68189D01*
Y-68135D01*
Y-68081D01*
Y-68027D01*
Y-67973D01*
Y-67919D01*
Y-67865D01*
Y-67810D01*
Y-67756D01*
Y-67702D01*
Y-67648D01*
Y-67594D01*
Y-67540D01*
Y-67486D01*
Y-67432D01*
Y-67378D01*
Y-67324D01*
Y-67270D01*
Y-67216D01*
Y-67162D01*
Y-67108D01*
Y-67054D01*
Y-67000D01*
Y-66945D01*
Y-66891D01*
Y-66837D01*
Y-66783D01*
Y-66729D01*
Y-66675D01*
Y-66621D01*
Y-66567D01*
Y-66513D01*
Y-66459D01*
Y-66405D01*
Y-66351D01*
Y-66297D01*
Y-66243D01*
Y-66189D01*
Y-66135D01*
Y-66080D01*
Y-66026D01*
Y-65972D01*
Y-65918D01*
Y-65864D01*
Y-65810D01*
Y-65756D01*
Y-65702D01*
Y-65648D01*
Y-65594D01*
Y-65540D01*
Y-65486D01*
Y-65432D01*
Y-65378D01*
Y-65324D01*
Y-65270D01*
Y-65215D01*
Y-65161D01*
Y-65107D01*
Y-65053D01*
Y-64999D01*
Y-64945D01*
Y-64891D01*
Y-64837D01*
Y-64783D01*
Y-64729D01*
Y-64675D01*
Y-64621D01*
Y-64567D01*
Y-64513D01*
Y-64459D01*
Y-64405D01*
Y-64350D01*
Y-64296D01*
Y-64242D01*
Y-64188D01*
Y-64134D01*
Y-64080D01*
Y-64026D01*
Y-63972D01*
Y-63918D01*
Y-63864D01*
Y-63810D01*
Y-63756D01*
Y-63702D01*
Y-63648D01*
Y-63594D01*
Y-63540D01*
Y-63485D01*
Y-63431D01*
Y-63377D01*
Y-63323D01*
Y-63269D01*
Y-63215D01*
Y-63161D01*
Y-63107D01*
Y-63053D01*
Y-62999D01*
Y-62945D01*
Y-62891D01*
Y-62837D01*
Y-62783D01*
Y-62729D01*
Y-62675D01*
Y-62621D01*
Y-62566D01*
Y-62512D01*
Y-62458D01*
Y-62404D01*
Y-62350D01*
Y-62296D01*
Y-62242D01*
Y-62188D01*
Y-62134D01*
Y-62080D01*
Y-62026D01*
Y-61972D01*
Y-61918D01*
Y-61864D01*
Y-61810D01*
Y-61756D01*
Y-61702D01*
Y-61647D01*
Y-61593D01*
Y-61539D01*
Y-61485D01*
Y-61431D01*
Y-61377D01*
Y-61323D01*
Y-61269D01*
Y-61215D01*
Y-61161D01*
Y-61107D01*
Y-61053D01*
Y-60999D01*
Y-60945D01*
Y-60891D01*
Y-60836D01*
Y-60782D01*
Y-60728D01*
Y-60674D01*
Y-60620D01*
Y-60566D01*
Y-60512D01*
Y-60458D01*
Y-60404D01*
Y-60350D01*
Y-60296D01*
Y-60242D01*
Y-60188D01*
Y-60134D01*
Y-60080D01*
Y-60026D01*
Y-59971D01*
Y-59917D01*
Y-59863D01*
Y-59809D01*
Y-59755D01*
Y-59701D01*
Y-59647D01*
Y-59593D01*
Y-59539D01*
Y-59485D01*
Y-59431D01*
Y-59377D01*
Y-59323D01*
Y-59269D01*
Y-59215D01*
Y-59161D01*
Y-59106D01*
Y-59052D01*
Y-58998D01*
Y-58944D01*
Y-58890D01*
Y-58836D01*
Y-58782D01*
Y-58728D01*
Y-58674D01*
Y-58620D01*
Y-58566D01*
Y-58512D01*
Y-58458D01*
Y-58404D01*
Y-58350D01*
Y-58296D01*
Y-58241D01*
Y-58187D01*
Y-58133D01*
Y-58079D01*
Y-58025D01*
Y-57971D01*
Y-57917D01*
Y-57863D01*
Y-57809D01*
Y-57755D01*
Y-57701D01*
Y-57647D01*
Y-57593D01*
Y-57539D01*
Y-57485D01*
Y-57431D01*
Y-57376D01*
Y-57322D01*
Y-57268D01*
Y-57214D01*
Y-57160D01*
Y-57106D01*
Y-57052D01*
Y-56998D01*
Y-56944D01*
Y-56890D01*
Y-56836D01*
Y-56782D01*
Y-56728D01*
Y-56674D01*
Y-56620D01*
Y-56566D01*
Y-56511D01*
Y-56457D01*
Y-56403D01*
Y-56349D01*
Y-56295D01*
Y-56241D01*
Y-56187D01*
Y-56133D01*
Y-56079D01*
Y-56025D01*
Y-55971D01*
Y-55917D01*
Y-55863D01*
Y-55809D01*
Y-55755D01*
Y-55701D01*
Y-55647D01*
Y-55592D01*
Y-55538D01*
Y-55484D01*
Y-55430D01*
Y-55376D01*
Y-55322D01*
Y-55268D01*
Y-55214D01*
Y-55160D01*
Y-55106D01*
Y-55052D01*
Y-54998D01*
Y-54944D01*
Y-54890D01*
Y-54836D01*
Y-54782D01*
Y-54728D01*
Y-54673D01*
Y-54619D01*
Y-54565D01*
Y-54511D01*
Y-54457D01*
Y-54403D01*
Y-54349D01*
Y-54295D01*
Y-54241D01*
Y-54187D01*
Y-54133D01*
Y-54079D01*
Y-54025D01*
Y-53971D01*
Y-53917D01*
Y-53863D01*
Y-53808D01*
Y-53754D01*
Y-53700D01*
Y-53646D01*
Y-53592D01*
Y-53538D01*
Y-53484D01*
Y-53430D01*
Y-53376D01*
Y-53322D01*
Y-53268D01*
Y-53214D01*
Y-53160D01*
Y-53106D01*
Y-53052D01*
Y-52997D01*
Y-52943D01*
Y-52889D01*
Y-52835D01*
Y-52781D01*
Y-52727D01*
Y-52673D01*
Y-52619D01*
Y-52565D01*
Y-52511D01*
Y-52457D01*
Y-52403D01*
Y-52349D01*
Y-52295D01*
Y-52241D01*
Y-52187D01*
Y-52132D01*
Y-52078D01*
Y-52024D01*
Y-51970D01*
Y-51916D01*
Y-51862D01*
Y-51808D01*
Y-51754D01*
Y-51700D01*
Y-51646D01*
Y-51592D01*
Y-51538D01*
Y-51484D01*
Y-51430D01*
Y-51376D01*
Y-51322D01*
Y-51267D01*
Y-51213D01*
Y-51159D01*
Y-51105D01*
Y-51051D01*
Y-50997D01*
Y-50943D01*
Y-50889D01*
Y-50835D01*
Y-50781D01*
Y-50727D01*
Y-50673D01*
Y-50619D01*
Y-50565D01*
Y-50511D01*
Y-50457D01*
Y-50402D01*
Y-50348D01*
Y-50294D01*
Y-50240D01*
Y-50186D01*
Y-50132D01*
Y-50078D01*
Y-50024D01*
Y-49970D01*
Y-49916D01*
Y-49862D01*
Y-49808D01*
Y-49754D01*
Y-49700D01*
Y-49646D01*
Y-49592D01*
Y-49538D01*
Y-49483D01*
Y-49429D01*
Y-49375D01*
Y-49321D01*
Y-49267D01*
Y-49213D01*
Y-49159D01*
Y-49105D01*
Y-49051D01*
Y-48997D01*
Y-48943D01*
Y-48889D01*
Y-48835D01*
Y-48781D01*
Y-48727D01*
Y-48673D01*
Y-48619D01*
Y-48564D01*
Y-48510D01*
Y-48456D01*
Y-48402D01*
Y-48348D01*
Y-48294D01*
Y-48240D01*
Y-48186D01*
Y-48132D01*
Y-48078D01*
Y-48024D01*
Y-47970D01*
Y-47916D01*
Y-47862D01*
Y-47807D01*
Y-47754D01*
Y-47699D01*
Y-47645D01*
Y-47591D01*
Y-47537D01*
Y-47483D01*
Y-47429D01*
Y-47375D01*
Y-47321D01*
Y-47267D01*
Y-47213D01*
Y-47159D01*
Y-47105D01*
Y-47051D01*
Y-46997D01*
Y-46942D01*
Y-46889D01*
Y-46834D01*
Y-46780D01*
Y-46726D01*
Y-46672D01*
Y-46618D01*
Y-46564D01*
Y-46510D01*
Y-46456D01*
Y-46402D01*
Y-46348D01*
Y-46294D01*
Y-46240D01*
Y-46186D01*
Y-46132D01*
Y-46077D01*
Y-46023D01*
Y-45969D01*
Y-45915D01*
Y-45861D01*
Y-45807D01*
Y-45753D01*
Y-45699D01*
Y-45645D01*
Y-45591D01*
Y-45537D01*
Y-45483D01*
Y-45429D01*
Y-45375D01*
Y-45321D01*
Y-45267D01*
Y-45213D01*
Y-45158D01*
Y-45104D01*
Y-45050D01*
Y-44996D01*
Y-44942D01*
Y-44888D01*
Y-44834D01*
Y-44780D01*
Y-44726D01*
Y-44672D01*
Y-44618D01*
Y-44564D01*
Y-44510D01*
Y-44456D01*
Y-44402D01*
Y-44348D01*
Y-44293D01*
Y-44239D01*
Y-44185D01*
Y-44131D01*
Y-44077D01*
Y-44023D01*
Y-43969D01*
Y-43915D01*
Y-43861D01*
Y-43807D01*
Y-43753D01*
Y-43699D01*
Y-43645D01*
Y-43591D01*
Y-43537D01*
Y-43483D01*
Y-43429D01*
Y-43374D01*
Y-43320D01*
Y-43266D01*
Y-43212D01*
Y-43158D01*
Y-43104D01*
Y-43050D01*
Y-42996D01*
Y-42942D01*
Y-42888D01*
Y-42834D01*
Y-42780D01*
Y-42726D01*
Y-42672D01*
Y-42618D01*
Y-42564D01*
Y-42509D01*
Y-42455D01*
Y-42401D01*
Y-42347D01*
Y-42293D01*
Y-42239D01*
Y-42185D01*
Y-42131D01*
Y-42077D01*
Y-42023D01*
Y-41969D01*
Y-41915D01*
Y-41861D01*
Y-41807D01*
Y-41753D01*
Y-41699D01*
Y-41644D01*
Y-41590D01*
Y-41536D01*
Y-41482D01*
Y-41428D01*
Y-41374D01*
Y-41320D01*
Y-41266D01*
Y-41212D01*
Y-41158D01*
Y-41104D01*
Y-41050D01*
Y-40996D01*
Y-40942D01*
Y-40888D01*
Y-40834D01*
Y-40780D01*
Y-40725D01*
Y-40671D01*
Y-40617D01*
Y-40563D01*
Y-40509D01*
Y-40455D01*
Y-40401D01*
Y-40347D01*
Y-40293D01*
Y-40239D01*
Y-40185D01*
Y-40131D01*
Y-40077D01*
Y-40023D01*
Y-39968D01*
Y-39915D01*
Y-39860D01*
Y-39806D01*
Y-39752D01*
Y-39698D01*
Y-39644D01*
Y-39590D01*
Y-39536D01*
Y-39482D01*
Y-39428D01*
Y-39374D01*
Y-39320D01*
Y-39266D01*
Y-39212D01*
Y-39158D01*
Y-39103D01*
Y-39050D01*
Y-38995D01*
Y-38941D01*
Y-38887D01*
Y-38833D01*
Y-38779D01*
Y-38725D01*
Y-38671D01*
Y-38617D01*
Y-38563D01*
Y-38509D01*
Y-38455D01*
Y-38401D01*
Y-38347D01*
Y-38293D01*
Y-38238D01*
Y-38184D01*
Y-38130D01*
Y-38076D01*
Y-38022D01*
Y-37968D01*
Y-37914D01*
Y-37860D01*
Y-37806D01*
Y-37752D01*
Y-37698D01*
Y-37644D01*
Y-37590D01*
Y-37536D01*
Y-37482D01*
Y-37428D01*
Y-37374D01*
Y-37319D01*
Y-37265D01*
Y-37211D01*
Y-37157D01*
Y-37103D01*
Y-37049D01*
Y-36995D01*
Y-36941D01*
Y-36887D01*
Y-36833D01*
Y-36779D01*
Y-36725D01*
Y-36671D01*
Y-36617D01*
Y-36563D01*
Y-36509D01*
Y-36454D01*
Y-36400D01*
Y-36346D01*
Y-36292D01*
Y-36238D01*
Y-36184D01*
Y-36130D01*
Y-36076D01*
Y-36022D01*
Y-35968D01*
Y-35914D01*
Y-35860D01*
Y-35806D01*
Y-35752D01*
Y-35698D01*
Y-35644D01*
Y-35590D01*
Y-35535D01*
Y-35481D01*
Y-35427D01*
Y-35373D01*
Y-35319D01*
Y-35265D01*
Y-35211D01*
Y-35157D01*
Y-35103D01*
Y-35049D01*
Y-34995D01*
Y-34941D01*
Y-34887D01*
Y-34833D01*
Y-34779D01*
Y-34725D01*
Y-34670D01*
Y-34616D01*
Y-34562D01*
Y-34508D01*
Y-34454D01*
Y-34400D01*
Y-34346D01*
Y-34292D01*
Y-34238D01*
Y-34184D01*
Y-34130D01*
Y-34076D01*
Y-34022D01*
Y-33968D01*
Y-33914D01*
Y-33860D01*
Y-33806D01*
Y-33751D01*
Y-33697D01*
Y-33643D01*
Y-33589D01*
Y-33535D01*
Y-33481D01*
Y-33427D01*
Y-33373D01*
Y-33319D01*
Y-33265D01*
Y-33211D01*
Y-33157D01*
Y-33103D01*
Y-33049D01*
Y-32994D01*
Y-32941D01*
Y-32886D01*
Y-32832D01*
Y-32778D01*
Y-32724D01*
Y-32670D01*
Y-32616D01*
Y-32562D01*
Y-32508D01*
Y-32454D01*
Y-32400D01*
Y-32346D01*
Y-32292D01*
Y-32238D01*
Y-32184D01*
Y-32129D01*
Y-32076D01*
Y-32021D01*
Y-31967D01*
Y-31913D01*
Y-31859D01*
Y-31805D01*
Y-31751D01*
Y-31697D01*
Y-31643D01*
Y-31589D01*
Y-31535D01*
Y-31481D01*
Y-31427D01*
Y-31373D01*
Y-31319D01*
Y-31265D01*
Y-31211D01*
Y-31156D01*
Y-31102D01*
Y-31048D01*
Y-30994D01*
Y-30940D01*
Y-30886D01*
Y-30832D01*
Y-30778D01*
Y-30724D01*
Y-30670D01*
Y-30616D01*
Y-30562D01*
Y-30508D01*
Y-30454D01*
Y-30400D01*
Y-30345D01*
Y-30291D01*
Y-30237D01*
Y-30183D01*
Y-30129D01*
Y-30075D01*
Y-30021D01*
Y-29967D01*
Y-29913D01*
Y-29859D01*
Y-29805D01*
Y-29751D01*
Y-29697D01*
Y-29643D01*
Y-29589D01*
Y-29535D01*
Y-29480D01*
Y-29426D01*
Y-29372D01*
Y-29318D01*
Y-29264D01*
Y-29210D01*
Y-29156D01*
Y-29102D01*
Y-29048D01*
Y-28994D01*
Y-28940D01*
Y-28886D01*
Y-28832D01*
Y-28778D01*
Y-28724D01*
Y-28670D01*
Y-28615D01*
Y-28561D01*
Y-28507D01*
Y-28453D01*
Y-28399D01*
Y-28345D01*
Y-28291D01*
Y-28237D01*
Y-28183D01*
Y-28129D01*
Y-28075D01*
Y-28021D01*
Y-27967D01*
Y-27913D01*
Y-27859D01*
Y-27805D01*
Y-27751D01*
Y-27696D01*
Y-27642D01*
Y-27588D01*
Y-27534D01*
Y-27480D01*
Y-27426D01*
Y-27372D01*
Y-27318D01*
Y-27264D01*
Y-27210D01*
Y-27156D01*
Y-27102D01*
Y-27048D01*
Y-26994D01*
Y-26940D01*
Y-26886D01*
Y-26831D01*
Y-26777D01*
Y-26723D01*
Y-26669D01*
Y-26615D01*
Y-26561D01*
Y-26507D01*
Y-26453D01*
Y-26399D01*
Y-26345D01*
Y-26291D01*
Y-26237D01*
Y-26183D01*
Y-26129D01*
Y-26075D01*
Y-26021D01*
Y-25967D01*
Y-25912D01*
Y-25858D01*
Y-25804D01*
Y-25750D01*
Y-25696D01*
Y-25642D01*
Y-25588D01*
Y-25534D01*
Y-25480D01*
Y-25426D01*
Y-25372D01*
Y-25318D01*
Y-25264D01*
Y-25210D01*
Y-25155D01*
Y-25102D01*
Y-25047D01*
Y-24993D01*
Y-24939D01*
Y-24885D01*
Y-24831D01*
Y-24777D01*
Y-24723D01*
Y-24669D01*
Y-24615D01*
Y-24561D01*
Y-24507D01*
Y-24453D01*
Y-24399D01*
Y-24345D01*
Y-24291D01*
Y-24237D01*
Y-24182D01*
Y-24128D01*
Y-24074D01*
Y-24020D01*
Y-23966D01*
Y-23912D01*
Y-23858D01*
Y-23804D01*
Y-23750D01*
Y-23696D01*
Y-23642D01*
Y-23588D01*
Y-23534D01*
Y-23480D01*
Y-23426D01*
Y-23371D01*
Y-23317D01*
Y-23263D01*
Y-23209D01*
Y-23155D01*
Y-23101D01*
Y-23047D01*
Y-22993D01*
Y-22939D01*
Y-22885D01*
Y-22831D01*
Y-22777D01*
Y-22723D01*
Y-22669D01*
Y-22615D01*
Y-22561D01*
Y-22506D01*
Y-22452D01*
Y-22398D01*
Y-22344D01*
Y-22290D01*
Y-22236D01*
Y-22182D01*
Y-22128D01*
Y-22074D01*
Y-22020D01*
Y-21966D01*
Y-21912D01*
Y-21858D01*
Y-21804D01*
Y-21750D01*
Y-21696D01*
Y-21642D01*
Y-21587D01*
Y-21533D01*
Y-21479D01*
Y-21425D01*
Y-21371D01*
Y-21317D01*
Y-21263D01*
Y-21209D01*
Y-21155D01*
Y-21101D01*
Y-21047D01*
Y-20993D01*
Y-20939D01*
Y-20885D01*
Y-20831D01*
Y-20776D01*
Y-20722D01*
Y-20668D01*
Y-20614D01*
Y-20560D01*
Y-20506D01*
Y-20452D01*
Y-20398D01*
Y-20344D01*
Y-20290D01*
Y-20236D01*
Y-20182D01*
Y-20128D01*
Y-20074D01*
Y-20020D01*
Y-19966D01*
Y-19911D01*
Y-19858D01*
Y-19803D01*
Y-19749D01*
Y-19695D01*
Y-19641D01*
Y-19587D01*
Y-19533D01*
Y-19479D01*
Y-19425D01*
Y-19371D01*
Y-19317D01*
Y-19263D01*
Y-19209D01*
Y-19155D01*
Y-19101D01*
Y-19047D01*
Y-18993D01*
Y-18938D01*
Y-18884D01*
Y-18830D01*
Y-18776D01*
Y-18722D01*
Y-18668D01*
Y-18614D01*
Y-18560D01*
Y-18506D01*
Y-18452D01*
Y-18398D01*
Y-18344D01*
Y-18290D01*
Y-18236D01*
Y-18181D01*
Y-18127D01*
Y-18073D01*
Y-18019D01*
Y-17965D01*
Y-17911D01*
Y-17857D01*
Y-17803D01*
Y-17749D01*
Y-17695D01*
Y-17641D01*
Y-17587D01*
Y-17533D01*
Y-17479D01*
Y-17425D01*
Y-17371D01*
Y-17317D01*
Y-17263D01*
Y-17208D01*
Y-17154D01*
Y-17100D01*
Y-17046D01*
Y-16992D01*
Y-16938D01*
Y-16884D01*
Y-16830D01*
Y-16776D01*
Y-16722D01*
Y-16668D01*
Y-16614D01*
Y-16560D01*
Y-16506D01*
Y-16452D01*
Y-16398D01*
Y-16343D01*
Y-16289D01*
Y-16235D01*
Y-16181D01*
Y-16127D01*
Y-16073D01*
Y-16019D01*
Y-15965D01*
Y-15911D01*
Y-15857D01*
Y-15803D01*
Y-15749D01*
Y-15695D01*
Y-15641D01*
Y-15587D01*
Y-15532D01*
Y-15478D01*
Y-15424D01*
Y-15370D01*
Y-15316D01*
Y-15262D01*
Y-15208D01*
Y-15154D01*
Y-15100D01*
Y-15046D01*
Y-14992D01*
Y-14938D01*
Y-14884D01*
Y-14830D01*
Y-14776D01*
Y-14722D01*
Y-14668D01*
Y-14614D01*
Y-14559D01*
Y-14505D01*
Y-14451D01*
Y-14397D01*
Y-14343D01*
Y-14289D01*
Y-14235D01*
Y-14181D01*
Y-14127D01*
Y-14073D01*
Y-14019D01*
Y-13965D01*
Y-13911D01*
Y-13857D01*
Y-13803D01*
Y-13748D01*
Y-13694D01*
Y-13640D01*
Y-13586D01*
Y-13532D01*
Y-13478D01*
Y-13424D01*
Y-13370D01*
Y-13316D01*
Y-13262D01*
Y-13208D01*
Y-13154D01*
Y-13100D01*
Y-13046D01*
Y-12992D01*
Y-12937D01*
Y-12883D01*
Y-12829D01*
Y-12775D01*
Y-12721D01*
Y-12667D01*
Y-12613D01*
Y-12559D01*
Y-12505D01*
Y-12451D01*
Y-12397D01*
Y-12343D01*
Y-12289D01*
Y-12235D01*
Y-12181D01*
Y-12127D01*
Y-12072D01*
Y-12019D01*
Y-11964D01*
Y-11910D01*
Y-11856D01*
Y-11802D01*
Y-11748D01*
Y-11694D01*
Y-11640D01*
Y-11586D01*
Y-11532D01*
Y-11478D01*
Y-11424D01*
Y-11370D01*
Y-11316D01*
Y-11262D01*
Y-11208D01*
Y-11153D01*
Y-11099D01*
Y-11045D01*
Y-10991D01*
Y-10937D01*
Y-10883D01*
Y-10829D01*
Y-10775D01*
Y-10721D01*
Y-10667D01*
Y-10613D01*
Y-10559D01*
Y-10505D01*
Y-10451D01*
X396955Y-10398D01*
X396965Y-10347D01*
X396982Y-10297D01*
X397005Y-10250D01*
X397005Y-10250D01*
Y-10234D01*
Y-10180D01*
X397009Y-10128D01*
X397019Y-10077D01*
X397036Y-10027D01*
X397059Y-9980D01*
X397059Y-9979D01*
Y-9964D01*
X397063Y-9912D01*
X397073Y-9860D01*
X397090Y-9811D01*
X397113Y-9764D01*
X397134Y-9733D01*
X397144Y-9703D01*
X397167Y-9656D01*
X397170Y-9651D01*
X397171Y-9641D01*
X397181Y-9590D01*
X397198Y-9540D01*
X397221Y-9493D01*
X397242Y-9463D01*
X397244Y-9455D01*
X397252Y-9432D01*
X397275Y-9385D01*
X397296Y-9354D01*
X397297Y-9350D01*
X397306Y-9324D01*
X397329Y-9277D01*
X397350Y-9246D01*
X397360Y-9216D01*
X397383Y-9169D01*
X397404Y-9138D01*
X397414Y-9108D01*
X397437Y-9061D01*
X397466Y-9017D01*
X397501Y-8978D01*
X397516Y-8965D01*
X397522Y-8946D01*
X397546Y-8899D01*
X397575Y-8855D01*
X397609Y-8816D01*
X397638Y-8790D01*
X397663Y-8762D01*
X397678Y-8749D01*
X397685Y-8730D01*
X397708Y-8682D01*
X397737Y-8639D01*
X397771Y-8599D01*
X397800Y-8574D01*
X397826Y-8545D01*
X397840Y-8532D01*
X397854Y-8520D01*
X397880Y-8491D01*
X397908Y-8466D01*
X397934Y-8437D01*
X397962Y-8412D01*
X397988Y-8383D01*
X398016Y-8358D01*
X398042Y-8329D01*
X398071Y-8304D01*
X398096Y-8275D01*
X398125Y-8250D01*
X398150Y-8221D01*
X398179Y-8196D01*
X398204Y-8167D01*
X398243Y-8132D01*
X398287Y-8103D01*
X398334Y-8080D01*
X398353Y-8073D01*
X398366Y-8059D01*
X398395Y-8033D01*
X398420Y-8005D01*
X398460Y-7970D01*
X398503Y-7941D01*
X398550Y-7918D01*
X398569Y-7911D01*
X398582Y-7897D01*
X398622Y-7862D01*
X398665Y-7833D01*
X398712Y-7810D01*
X398743Y-7799D01*
X398774Y-7779D01*
X398820Y-7756D01*
X398851Y-7745D01*
X398882Y-7725D01*
X398929Y-7702D01*
X398959Y-7691D01*
X398990Y-7671D01*
X399037Y-7648D01*
X399067Y-7637D01*
X399098Y-7617D01*
X399145Y-7593D01*
X399195Y-7577D01*
X399246Y-7566D01*
X399255Y-7566D01*
X399260Y-7563D01*
X399307Y-7539D01*
X399337Y-7529D01*
X399368Y-7508D01*
X399415Y-7485D01*
X399465Y-7468D01*
X399516Y-7458D01*
X399569Y-7455D01*
X399584D01*
X399584Y-7455D01*
X399631Y-7431D01*
X399681Y-7414D01*
X399732Y-7404D01*
X399785Y-7401D01*
X399800D01*
X399801Y-7400D01*
X399848Y-7377D01*
X399897Y-7360D01*
X399949Y-7350D01*
X400001Y-7347D01*
X400341D01*
X400341Y-7346D01*
X400388Y-7323D01*
X400438Y-7306D01*
X400489Y-7296D01*
X400542Y-7293D01*
X407408D01*
X407460Y-7296D01*
D02*
G37*
%LPC*%
G36*
X357145Y-21285D02*
X351222D01*
X351221Y-21286D01*
X351174Y-21309D01*
X351125Y-21326D01*
X351073Y-21336D01*
X351021Y-21340D01*
X350967D01*
X350944Y-21338D01*
X350936Y-21355D01*
X350935Y-21356D01*
Y-21371D01*
Y-21425D01*
Y-21479D01*
Y-21533D01*
Y-21587D01*
Y-21642D01*
Y-21696D01*
Y-21750D01*
Y-21804D01*
Y-21858D01*
Y-21912D01*
Y-21966D01*
Y-22020D01*
Y-22074D01*
Y-22128D01*
Y-22182D01*
Y-22236D01*
Y-22290D01*
Y-22344D01*
Y-22398D01*
Y-22452D01*
Y-22506D01*
Y-22561D01*
Y-22615D01*
Y-22669D01*
Y-22723D01*
Y-22777D01*
Y-22831D01*
Y-22885D01*
Y-22939D01*
Y-22993D01*
Y-23047D01*
Y-23101D01*
Y-23155D01*
Y-23209D01*
Y-23241D01*
X356535D01*
X356588Y-23244D01*
X356639Y-23255D01*
X356689Y-23271D01*
X356736Y-23295D01*
X356779Y-23324D01*
X356819Y-23358D01*
X356844Y-23387D01*
X356873Y-23412D01*
X356907Y-23452D01*
X356936Y-23495D01*
X356960Y-23542D01*
X356977Y-23592D01*
X356987Y-23643D01*
X356990Y-23696D01*
Y-23750D01*
Y-23804D01*
Y-23858D01*
Y-23912D01*
Y-23966D01*
Y-24020D01*
Y-24074D01*
Y-24128D01*
Y-24182D01*
Y-24237D01*
Y-24291D01*
Y-24345D01*
Y-24399D01*
Y-24453D01*
Y-24507D01*
Y-24561D01*
Y-24615D01*
Y-24669D01*
Y-24723D01*
Y-24777D01*
Y-24831D01*
Y-24885D01*
Y-24939D01*
Y-24993D01*
Y-25047D01*
Y-25102D01*
Y-25155D01*
Y-25210D01*
Y-25264D01*
Y-25318D01*
Y-25372D01*
Y-25426D01*
Y-25480D01*
Y-25534D01*
Y-25588D01*
X356987Y-25640D01*
X356977Y-25692D01*
X356960Y-25741D01*
X356936Y-25789D01*
X356907Y-25832D01*
X356873Y-25872D01*
X356844Y-25897D01*
X356819Y-25925D01*
X356779Y-25960D01*
X356736Y-25989D01*
X356689Y-26013D01*
X356639Y-26029D01*
X356588Y-26039D01*
X356535Y-26043D01*
X351800D01*
Y-26075D01*
Y-26129D01*
Y-26183D01*
Y-26237D01*
Y-26291D01*
Y-26345D01*
Y-26399D01*
Y-26453D01*
Y-26507D01*
Y-26561D01*
Y-26615D01*
Y-26669D01*
Y-26723D01*
Y-26777D01*
Y-26831D01*
Y-26886D01*
Y-26940D01*
Y-26994D01*
Y-27048D01*
Y-27102D01*
Y-27156D01*
Y-27210D01*
Y-27264D01*
Y-27318D01*
Y-27372D01*
Y-27426D01*
Y-27480D01*
Y-27534D01*
Y-27566D01*
X356535D01*
X356588Y-27569D01*
X356639Y-27580D01*
X356689Y-27596D01*
X356736Y-27620D01*
X356779Y-27649D01*
X356819Y-27683D01*
X356844Y-27712D01*
X356873Y-27737D01*
X356907Y-27777D01*
X356936Y-27820D01*
X356960Y-27867D01*
X356977Y-27917D01*
X356987Y-27968D01*
X356990Y-28021D01*
Y-28075D01*
Y-28129D01*
Y-28183D01*
Y-28237D01*
Y-28291D01*
Y-28345D01*
Y-28399D01*
Y-28453D01*
Y-28507D01*
Y-28561D01*
Y-28615D01*
Y-28670D01*
Y-28724D01*
Y-28778D01*
Y-28832D01*
Y-28886D01*
Y-28940D01*
Y-28994D01*
Y-29048D01*
Y-29102D01*
Y-29156D01*
Y-29210D01*
Y-29264D01*
Y-29318D01*
Y-29372D01*
Y-29426D01*
Y-29480D01*
Y-29535D01*
Y-29589D01*
Y-29643D01*
Y-29697D01*
Y-29751D01*
Y-29805D01*
Y-29859D01*
X356987Y-29911D01*
X356977Y-29963D01*
X356960Y-30012D01*
X356936Y-30059D01*
X356907Y-30103D01*
X356873Y-30142D01*
X356844Y-30168D01*
X356819Y-30196D01*
X356779Y-30231D01*
X356736Y-30260D01*
X356689Y-30283D01*
X356639Y-30300D01*
X356588Y-30310D01*
X356535Y-30314D01*
X350952D01*
X350951Y-30314D01*
X350941Y-30319D01*
X350936Y-30330D01*
X350935Y-30330D01*
Y-30345D01*
Y-30400D01*
Y-30454D01*
Y-30508D01*
Y-30562D01*
Y-30616D01*
Y-30670D01*
Y-30724D01*
Y-30778D01*
Y-30832D01*
Y-30886D01*
Y-30940D01*
Y-30994D01*
Y-31048D01*
Y-31102D01*
Y-31156D01*
Y-31211D01*
Y-31265D01*
Y-31319D01*
Y-31373D01*
Y-31427D01*
Y-31481D01*
Y-31535D01*
Y-31589D01*
Y-31643D01*
Y-31697D01*
Y-31751D01*
Y-31805D01*
Y-31859D01*
Y-31913D01*
Y-31967D01*
Y-32021D01*
Y-32076D01*
Y-32129D01*
Y-32184D01*
D01*
Y-32238D01*
Y-32253D01*
X350936Y-32254D01*
X350943Y-32269D01*
X357362D01*
X357362Y-32269D01*
X357409Y-32246D01*
X357459Y-32229D01*
X357510Y-32219D01*
X357562Y-32215D01*
X357578D01*
X357578Y-32215D01*
X357625Y-32192D01*
X357645Y-32185D01*
X357657Y-32171D01*
X357686Y-32145D01*
X357711Y-32116D01*
X357740Y-32091D01*
X357766Y-32062D01*
X357794Y-32037D01*
X357820Y-32008D01*
X357848Y-31983D01*
X357874Y-31954D01*
X357902Y-31929D01*
X357928Y-31900D01*
X357957Y-31875D01*
X357982Y-31846D01*
X358011Y-31821D01*
X358036Y-31792D01*
X358065Y-31767D01*
X358090Y-31738D01*
X358119Y-31713D01*
X358144Y-31684D01*
X358173Y-31659D01*
X358198Y-31630D01*
X358227Y-31605D01*
X358252Y-31576D01*
X358281Y-31550D01*
X358306Y-31522D01*
X358335Y-31496D01*
X358360Y-31468D01*
X358389Y-31442D01*
X358414Y-31414D01*
X358443Y-31388D01*
X358468Y-31359D01*
X358497Y-31334D01*
X358522Y-31306D01*
X358551Y-31280D01*
X358576Y-31251D01*
X358605Y-31226D01*
X358630Y-31197D01*
X358651Y-31179D01*
X358659Y-31172D01*
X358685Y-31143D01*
X358713Y-31118D01*
X358739Y-31089D01*
X358767Y-31064D01*
X358793Y-31035D01*
X358822Y-31010D01*
X358847Y-30981D01*
X358876Y-30956D01*
X358901Y-30927D01*
X358930Y-30902D01*
X358955Y-30873D01*
X358984Y-30848D01*
X359009Y-30819D01*
X359024Y-30806D01*
X359030Y-30787D01*
X359053Y-30740D01*
X359074Y-30709D01*
X359084Y-30679D01*
X359107Y-30632D01*
X359108Y-30631D01*
Y-30616D01*
Y-30562D01*
X359111Y-30509D01*
X359121Y-30458D01*
X359138Y-30408D01*
X359161Y-30361D01*
X359162Y-30361D01*
Y-30345D01*
Y-30291D01*
Y-30237D01*
Y-30183D01*
Y-30129D01*
Y-30075D01*
Y-30021D01*
Y-29967D01*
Y-29913D01*
Y-29859D01*
Y-29805D01*
Y-29751D01*
Y-29697D01*
Y-29643D01*
Y-29589D01*
Y-29535D01*
Y-29480D01*
Y-29426D01*
Y-29372D01*
Y-29318D01*
Y-29264D01*
Y-29210D01*
Y-29156D01*
Y-29102D01*
Y-29048D01*
Y-28994D01*
Y-28940D01*
Y-28886D01*
Y-28832D01*
Y-28778D01*
Y-28724D01*
Y-28670D01*
Y-28615D01*
Y-28561D01*
Y-28507D01*
Y-28453D01*
Y-28399D01*
Y-28345D01*
Y-28291D01*
Y-28237D01*
Y-28183D01*
Y-28129D01*
Y-28075D01*
Y-28021D01*
Y-27967D01*
Y-27913D01*
Y-27859D01*
Y-27805D01*
Y-27751D01*
Y-27696D01*
Y-27642D01*
Y-27588D01*
Y-27534D01*
Y-27480D01*
Y-27426D01*
Y-27372D01*
Y-27318D01*
Y-27264D01*
Y-27210D01*
Y-27156D01*
Y-27102D01*
Y-27048D01*
Y-26994D01*
Y-26940D01*
Y-26886D01*
Y-26831D01*
Y-26777D01*
Y-26723D01*
Y-26669D01*
Y-26615D01*
Y-26561D01*
Y-26507D01*
Y-26453D01*
Y-26399D01*
Y-26345D01*
Y-26291D01*
Y-26237D01*
Y-26183D01*
Y-26129D01*
Y-26075D01*
Y-26021D01*
Y-25967D01*
Y-25912D01*
Y-25858D01*
Y-25804D01*
Y-25750D01*
Y-25696D01*
Y-25642D01*
Y-25588D01*
Y-25534D01*
Y-25480D01*
Y-25426D01*
Y-25372D01*
Y-25318D01*
Y-25264D01*
Y-25210D01*
Y-25155D01*
Y-25102D01*
Y-25047D01*
Y-24993D01*
Y-24939D01*
Y-24885D01*
Y-24831D01*
Y-24777D01*
Y-24723D01*
Y-24669D01*
Y-24615D01*
Y-24561D01*
Y-24507D01*
Y-24453D01*
Y-24399D01*
Y-24345D01*
Y-24291D01*
Y-24237D01*
Y-24182D01*
Y-24128D01*
Y-24074D01*
Y-24020D01*
Y-23966D01*
Y-23912D01*
Y-23858D01*
Y-23804D01*
Y-23750D01*
Y-23696D01*
Y-23642D01*
Y-23588D01*
Y-23534D01*
Y-23480D01*
Y-23426D01*
Y-23371D01*
Y-23317D01*
Y-23263D01*
Y-23248D01*
X359161Y-23248D01*
X359138Y-23201D01*
X359121Y-23151D01*
X359111Y-23099D01*
X359108Y-23047D01*
Y-22993D01*
Y-22978D01*
X359107Y-22977D01*
X359084Y-22930D01*
X359067Y-22881D01*
X359059Y-22840D01*
X359038Y-22815D01*
X359009Y-22790D01*
X358984Y-22761D01*
X358955Y-22736D01*
X358930Y-22707D01*
X358901Y-22682D01*
X358876Y-22653D01*
X358868Y-22646D01*
X358847Y-22628D01*
X358835Y-22615D01*
X358821Y-22599D01*
X358818Y-22596D01*
X358793Y-22574D01*
X358767Y-22545D01*
X358739Y-22520D01*
X358713Y-22491D01*
X358685Y-22466D01*
X358659Y-22437D01*
X358630Y-22411D01*
X358605Y-22383D01*
X358576Y-22357D01*
X358551Y-22329D01*
X358522Y-22303D01*
X358503Y-22282D01*
X358497Y-22275D01*
X358468Y-22249D01*
X358443Y-22220D01*
X358414Y-22195D01*
X358389Y-22166D01*
X358375Y-22154D01*
X358360Y-22141D01*
X358335Y-22113D01*
X358306Y-22087D01*
X358281Y-22058D01*
X358252Y-22033D01*
X358241Y-22020D01*
X358227Y-22004D01*
X358198Y-21979D01*
X358173Y-21950D01*
X358144Y-21925D01*
X358119Y-21896D01*
X358090Y-21871D01*
X358065Y-21842D01*
X358064Y-21842D01*
X358036Y-21817D01*
X358031Y-21812D01*
X358011Y-21788D01*
X357982Y-21763D01*
X357957Y-21734D01*
X357928Y-21709D01*
X357902Y-21680D01*
X357874Y-21655D01*
X357848Y-21626D01*
X357820Y-21601D01*
X357794Y-21572D01*
X357766Y-21546D01*
X357740Y-21518D01*
X357736Y-21514D01*
X357711Y-21493D01*
X357686Y-21464D01*
X357657Y-21438D01*
X357645Y-21424D01*
X357625Y-21417D01*
X357578Y-21394D01*
X357574Y-21391D01*
X357564Y-21390D01*
X357513Y-21380D01*
X357463Y-21363D01*
X357416Y-21340D01*
X357416Y-21340D01*
X357346D01*
X357294Y-21336D01*
X357242Y-21326D01*
X357193Y-21309D01*
X357146Y-21286D01*
X357145Y-21285D01*
D02*
G37*
G36*
X386771D02*
X378848D01*
X378847Y-21286D01*
X378800Y-21309D01*
X378750Y-21326D01*
X378699Y-21336D01*
X378647Y-21340D01*
X378646D01*
X378639Y-21362D01*
X378615Y-21409D01*
X378615Y-21410D01*
Y-21425D01*
Y-21479D01*
Y-21533D01*
Y-21587D01*
Y-21642D01*
Y-21696D01*
Y-21750D01*
Y-21804D01*
Y-21858D01*
Y-21912D01*
Y-21966D01*
Y-22020D01*
Y-22074D01*
Y-22128D01*
Y-22182D01*
Y-22236D01*
Y-22290D01*
Y-22344D01*
Y-22398D01*
Y-22452D01*
Y-22506D01*
Y-22561D01*
Y-22615D01*
Y-22669D01*
Y-22723D01*
Y-22777D01*
Y-22831D01*
Y-22885D01*
Y-22939D01*
Y-22993D01*
Y-23047D01*
Y-23101D01*
Y-23155D01*
Y-23209D01*
Y-23263D01*
Y-23279D01*
X378615Y-23279D01*
X378639Y-23326D01*
X378652Y-23366D01*
X378692Y-23380D01*
X378739Y-23403D01*
X378739Y-23403D01*
X381133D01*
X381186Y-23407D01*
X381237Y-23417D01*
X381287Y-23434D01*
X381334Y-23457D01*
X381378Y-23486D01*
X381417Y-23520D01*
X381442Y-23549D01*
X381471Y-23575D01*
X381496Y-23603D01*
X381525Y-23629D01*
X381560Y-23668D01*
X381589Y-23712D01*
X381612Y-23759D01*
X381629Y-23808D01*
X381639Y-23860D01*
X381642Y-23912D01*
Y-23966D01*
Y-24020D01*
Y-24074D01*
Y-24128D01*
Y-24182D01*
Y-24237D01*
Y-24291D01*
Y-24345D01*
Y-24399D01*
Y-24453D01*
Y-24507D01*
Y-24561D01*
Y-24615D01*
Y-24669D01*
Y-24723D01*
Y-24777D01*
Y-24831D01*
Y-24885D01*
Y-24939D01*
Y-24993D01*
Y-25047D01*
Y-25102D01*
Y-25155D01*
Y-25210D01*
Y-25264D01*
Y-25318D01*
Y-25372D01*
Y-25426D01*
Y-25480D01*
Y-25534D01*
Y-25588D01*
Y-25642D01*
Y-25696D01*
Y-25750D01*
Y-25804D01*
Y-25858D01*
Y-25912D01*
Y-25967D01*
Y-26021D01*
Y-26075D01*
Y-26129D01*
Y-26183D01*
Y-26237D01*
Y-26291D01*
Y-26345D01*
Y-26399D01*
Y-26453D01*
Y-26507D01*
Y-26561D01*
Y-26615D01*
Y-26669D01*
Y-26723D01*
Y-26777D01*
Y-26831D01*
Y-26886D01*
Y-26940D01*
Y-26994D01*
Y-27048D01*
Y-27102D01*
Y-27156D01*
Y-27210D01*
Y-27264D01*
Y-27318D01*
Y-27372D01*
Y-27426D01*
Y-27480D01*
Y-27534D01*
Y-27588D01*
Y-27642D01*
Y-27696D01*
Y-27751D01*
Y-27805D01*
Y-27859D01*
Y-27913D01*
Y-27967D01*
Y-28021D01*
Y-28075D01*
Y-28129D01*
Y-28183D01*
Y-28237D01*
Y-28291D01*
Y-28345D01*
Y-28399D01*
Y-28453D01*
Y-28507D01*
Y-28561D01*
Y-28615D01*
Y-28670D01*
Y-28724D01*
Y-28778D01*
Y-28832D01*
Y-28886D01*
Y-28940D01*
Y-28994D01*
Y-29048D01*
Y-29102D01*
Y-29156D01*
Y-29210D01*
Y-29264D01*
Y-29318D01*
Y-29372D01*
Y-29426D01*
Y-29480D01*
Y-29535D01*
Y-29589D01*
Y-29643D01*
Y-29697D01*
Y-29751D01*
Y-29805D01*
Y-29859D01*
Y-29913D01*
Y-29967D01*
Y-30021D01*
Y-30075D01*
Y-30129D01*
Y-30183D01*
Y-30237D01*
Y-30291D01*
Y-30345D01*
Y-30400D01*
Y-30454D01*
Y-30508D01*
Y-30562D01*
Y-30616D01*
Y-30670D01*
Y-30724D01*
Y-30778D01*
Y-30832D01*
Y-30886D01*
Y-30940D01*
Y-30994D01*
Y-31048D01*
Y-31102D01*
Y-31156D01*
Y-31211D01*
Y-31265D01*
Y-31319D01*
Y-31373D01*
Y-31427D01*
Y-31481D01*
Y-31535D01*
Y-31589D01*
Y-31643D01*
Y-31697D01*
Y-31751D01*
Y-31805D01*
Y-31859D01*
Y-31913D01*
Y-31967D01*
Y-32021D01*
Y-32076D01*
Y-32129D01*
Y-32184D01*
D01*
Y-32199D01*
X381643Y-32199D01*
X381666Y-32246D01*
X381672Y-32264D01*
X381674Y-32269D01*
X383814D01*
Y-32238D01*
Y-32184D01*
D01*
Y-32129D01*
Y-32076D01*
Y-32021D01*
Y-31967D01*
Y-31913D01*
Y-31859D01*
Y-31805D01*
Y-31751D01*
Y-31697D01*
Y-31643D01*
Y-31589D01*
Y-31535D01*
Y-31481D01*
Y-31427D01*
Y-31373D01*
Y-31319D01*
Y-31265D01*
Y-31211D01*
Y-31156D01*
Y-31102D01*
Y-31048D01*
Y-30994D01*
Y-30940D01*
Y-30886D01*
Y-30832D01*
Y-30778D01*
Y-30724D01*
Y-30670D01*
Y-30616D01*
Y-30562D01*
Y-30508D01*
Y-30454D01*
Y-30400D01*
Y-30345D01*
Y-30291D01*
Y-30237D01*
Y-30183D01*
Y-30129D01*
Y-30075D01*
Y-30021D01*
Y-29967D01*
Y-29913D01*
Y-29859D01*
Y-29805D01*
Y-29751D01*
Y-29697D01*
Y-29643D01*
Y-29589D01*
Y-29535D01*
Y-29480D01*
Y-29426D01*
Y-29372D01*
Y-29318D01*
Y-29264D01*
Y-29210D01*
Y-29156D01*
Y-29102D01*
Y-29048D01*
Y-28994D01*
Y-28940D01*
Y-28886D01*
Y-28832D01*
Y-28778D01*
Y-28724D01*
Y-28670D01*
Y-28615D01*
Y-28561D01*
Y-28507D01*
Y-28453D01*
Y-28399D01*
Y-28345D01*
Y-28291D01*
Y-28237D01*
Y-28183D01*
Y-28129D01*
Y-28075D01*
Y-28021D01*
Y-27967D01*
Y-27913D01*
Y-27859D01*
Y-27805D01*
Y-27751D01*
Y-27696D01*
Y-27642D01*
Y-27588D01*
Y-27534D01*
Y-27480D01*
Y-27426D01*
Y-27372D01*
Y-27318D01*
Y-27264D01*
Y-27210D01*
Y-27156D01*
Y-27102D01*
Y-27048D01*
Y-26994D01*
Y-26940D01*
Y-26886D01*
Y-26831D01*
Y-26777D01*
Y-26723D01*
Y-26669D01*
Y-26615D01*
Y-26561D01*
Y-26507D01*
Y-26453D01*
Y-26399D01*
Y-26345D01*
Y-26291D01*
Y-26237D01*
Y-26183D01*
Y-26129D01*
Y-26075D01*
Y-26021D01*
Y-25967D01*
Y-25912D01*
Y-25858D01*
Y-25804D01*
Y-25750D01*
Y-25696D01*
Y-25642D01*
Y-25588D01*
Y-25534D01*
Y-25480D01*
Y-25426D01*
Y-25372D01*
Y-25318D01*
Y-25264D01*
Y-25210D01*
Y-25155D01*
Y-25102D01*
Y-25047D01*
Y-24993D01*
Y-24939D01*
Y-24885D01*
Y-24831D01*
Y-24777D01*
Y-24723D01*
Y-24669D01*
Y-24615D01*
Y-24561D01*
Y-24507D01*
Y-24453D01*
Y-24399D01*
Y-24345D01*
Y-24291D01*
Y-24237D01*
Y-24182D01*
Y-24128D01*
Y-24074D01*
Y-24020D01*
X383818Y-23968D01*
X383828Y-23916D01*
X383845Y-23867D01*
X383868Y-23820D01*
X383888Y-23789D01*
X383899Y-23759D01*
X383922Y-23712D01*
X383951Y-23668D01*
X383986Y-23629D01*
X384014Y-23603D01*
X384040Y-23575D01*
X384068Y-23549D01*
X384094Y-23520D01*
X384133Y-23486D01*
X384177Y-23457D01*
X384224Y-23434D01*
X384273Y-23417D01*
X384325Y-23407D01*
X384377Y-23403D01*
X386771D01*
X386772Y-23403D01*
X386819Y-23380D01*
X386838Y-23373D01*
X386842Y-23369D01*
Y-23317D01*
Y-23263D01*
Y-23209D01*
Y-23155D01*
Y-23101D01*
Y-23047D01*
Y-22993D01*
Y-22939D01*
Y-22885D01*
Y-22831D01*
Y-22777D01*
Y-22723D01*
Y-22669D01*
Y-22615D01*
Y-22561D01*
Y-22506D01*
Y-22452D01*
Y-22398D01*
Y-22344D01*
Y-22290D01*
Y-22236D01*
Y-22182D01*
Y-22128D01*
Y-22074D01*
Y-22020D01*
Y-21966D01*
Y-21912D01*
Y-21858D01*
Y-21804D01*
Y-21750D01*
Y-21696D01*
Y-21642D01*
Y-21587D01*
Y-21533D01*
Y-21479D01*
Y-21425D01*
Y-21371D01*
Y-21317D01*
Y-21317D01*
X386819Y-21309D01*
X386772Y-21286D01*
X386771Y-21285D01*
D02*
G37*
G36*
X377094D02*
X375009D01*
X375009Y-21286D01*
X374993Y-21294D01*
Y-21317D01*
Y-21371D01*
Y-21425D01*
Y-21479D01*
Y-21533D01*
Y-21587D01*
Y-21642D01*
Y-21696D01*
Y-21750D01*
Y-21804D01*
Y-21858D01*
Y-21912D01*
Y-21966D01*
Y-22020D01*
Y-22074D01*
Y-22128D01*
Y-22182D01*
Y-22236D01*
Y-22290D01*
Y-22344D01*
Y-22398D01*
Y-22452D01*
Y-22506D01*
Y-22561D01*
Y-22615D01*
Y-22669D01*
Y-22723D01*
Y-22777D01*
Y-22831D01*
Y-22885D01*
Y-22939D01*
Y-22993D01*
Y-23047D01*
Y-23101D01*
Y-23155D01*
Y-23209D01*
Y-23263D01*
Y-23317D01*
Y-23371D01*
Y-23426D01*
Y-23480D01*
Y-23534D01*
Y-23588D01*
Y-23642D01*
Y-23696D01*
Y-23750D01*
Y-23804D01*
Y-23858D01*
Y-23912D01*
Y-23966D01*
Y-24020D01*
Y-24074D01*
Y-24128D01*
Y-24182D01*
Y-24237D01*
Y-24291D01*
Y-24345D01*
Y-24399D01*
Y-24453D01*
Y-24507D01*
Y-24561D01*
Y-24615D01*
Y-24669D01*
Y-24723D01*
Y-24777D01*
Y-24831D01*
Y-24885D01*
Y-24939D01*
Y-24993D01*
Y-25047D01*
Y-25102D01*
Y-25155D01*
Y-25210D01*
Y-25264D01*
Y-25318D01*
Y-25372D01*
Y-25426D01*
Y-25480D01*
Y-25534D01*
Y-25588D01*
Y-25642D01*
Y-25696D01*
Y-25750D01*
Y-25804D01*
Y-25858D01*
Y-25912D01*
Y-25967D01*
Y-26021D01*
Y-26075D01*
Y-26129D01*
Y-26183D01*
Y-26237D01*
Y-26291D01*
Y-26345D01*
Y-26399D01*
Y-26453D01*
Y-26507D01*
Y-26561D01*
Y-26615D01*
Y-26669D01*
Y-26723D01*
Y-26777D01*
Y-26831D01*
Y-26886D01*
Y-26940D01*
Y-26994D01*
Y-27048D01*
Y-27102D01*
Y-27156D01*
Y-27210D01*
Y-27264D01*
Y-27318D01*
Y-27372D01*
Y-27426D01*
Y-27480D01*
Y-27534D01*
Y-27588D01*
Y-27642D01*
Y-27696D01*
Y-27751D01*
Y-27805D01*
Y-27859D01*
Y-27913D01*
Y-27967D01*
Y-28021D01*
Y-28075D01*
Y-28129D01*
Y-28183D01*
Y-28237D01*
Y-28291D01*
Y-28345D01*
Y-28399D01*
Y-28453D01*
Y-28507D01*
Y-28561D01*
Y-28615D01*
Y-28670D01*
Y-28724D01*
Y-28778D01*
Y-28832D01*
Y-28886D01*
Y-28940D01*
Y-28994D01*
Y-29048D01*
Y-29102D01*
Y-29156D01*
Y-29210D01*
Y-29264D01*
Y-29318D01*
Y-29372D01*
Y-29426D01*
Y-29480D01*
Y-29535D01*
Y-29589D01*
Y-29643D01*
Y-29697D01*
Y-29751D01*
Y-29805D01*
Y-29859D01*
Y-29913D01*
Y-29967D01*
Y-30021D01*
Y-30075D01*
Y-30129D01*
Y-30183D01*
Y-30237D01*
Y-30291D01*
Y-30345D01*
Y-30400D01*
Y-30454D01*
Y-30508D01*
Y-30562D01*
Y-30616D01*
Y-30670D01*
Y-30724D01*
Y-30778D01*
Y-30832D01*
Y-30886D01*
Y-30940D01*
Y-30994D01*
Y-31048D01*
Y-31102D01*
Y-31156D01*
Y-31211D01*
Y-31265D01*
Y-31319D01*
Y-31373D01*
Y-31427D01*
Y-31481D01*
Y-31535D01*
Y-31589D01*
Y-31643D01*
Y-31697D01*
Y-31751D01*
Y-31805D01*
Y-31859D01*
Y-31913D01*
Y-31967D01*
Y-32021D01*
Y-32076D01*
Y-32129D01*
Y-32184D01*
Y-32238D01*
Y-32269D01*
X377156D01*
X377164Y-32254D01*
X377165Y-32253D01*
Y-32238D01*
Y-32184D01*
D01*
Y-32129D01*
Y-32076D01*
Y-32021D01*
Y-31967D01*
Y-31913D01*
Y-31859D01*
Y-31805D01*
Y-31751D01*
Y-31697D01*
Y-31643D01*
Y-31589D01*
Y-31535D01*
Y-31481D01*
Y-31427D01*
Y-31373D01*
Y-31319D01*
Y-31265D01*
Y-31211D01*
Y-31156D01*
Y-31102D01*
Y-31048D01*
Y-30994D01*
Y-30940D01*
Y-30886D01*
Y-30832D01*
Y-30778D01*
Y-30724D01*
Y-30670D01*
Y-30616D01*
Y-30562D01*
Y-30508D01*
Y-30454D01*
Y-30400D01*
Y-30345D01*
Y-30291D01*
Y-30237D01*
Y-30183D01*
Y-30129D01*
Y-30075D01*
Y-30021D01*
Y-29967D01*
Y-29913D01*
Y-29859D01*
Y-29805D01*
Y-29751D01*
Y-29697D01*
Y-29643D01*
Y-29589D01*
Y-29535D01*
Y-29480D01*
Y-29426D01*
Y-29372D01*
Y-29318D01*
Y-29264D01*
Y-29210D01*
Y-29156D01*
Y-29102D01*
Y-29048D01*
Y-28994D01*
Y-28940D01*
Y-28886D01*
Y-28832D01*
Y-28778D01*
Y-28724D01*
Y-28670D01*
Y-28615D01*
Y-28561D01*
Y-28507D01*
Y-28453D01*
Y-28399D01*
Y-28345D01*
Y-28291D01*
Y-28237D01*
Y-28183D01*
Y-28129D01*
Y-28075D01*
Y-28021D01*
Y-27967D01*
Y-27913D01*
Y-27859D01*
Y-27805D01*
Y-27751D01*
Y-27696D01*
Y-27642D01*
Y-27588D01*
Y-27534D01*
Y-27480D01*
Y-27426D01*
Y-27372D01*
Y-27318D01*
Y-27264D01*
Y-27210D01*
Y-27156D01*
Y-27102D01*
Y-27048D01*
Y-26994D01*
Y-26940D01*
Y-26886D01*
Y-26831D01*
Y-26777D01*
Y-26723D01*
Y-26669D01*
Y-26615D01*
Y-26561D01*
Y-26507D01*
Y-26453D01*
Y-26399D01*
Y-26345D01*
Y-26291D01*
Y-26237D01*
Y-26183D01*
Y-26129D01*
Y-26075D01*
Y-26021D01*
Y-25967D01*
Y-25912D01*
Y-25858D01*
Y-25804D01*
Y-25750D01*
Y-25696D01*
Y-25642D01*
Y-25588D01*
Y-25534D01*
Y-25480D01*
Y-25426D01*
Y-25372D01*
Y-25318D01*
Y-25264D01*
Y-25210D01*
Y-25155D01*
Y-25102D01*
Y-25047D01*
Y-24993D01*
Y-24939D01*
Y-24885D01*
Y-24831D01*
Y-24777D01*
Y-24723D01*
Y-24669D01*
Y-24615D01*
Y-24561D01*
Y-24507D01*
Y-24453D01*
Y-24399D01*
Y-24345D01*
Y-24291D01*
Y-24237D01*
Y-24182D01*
Y-24128D01*
Y-24074D01*
Y-24020D01*
Y-23966D01*
Y-23912D01*
Y-23858D01*
Y-23804D01*
Y-23750D01*
Y-23696D01*
Y-23642D01*
Y-23588D01*
Y-23534D01*
Y-23480D01*
Y-23426D01*
Y-23371D01*
Y-23317D01*
Y-23263D01*
Y-23209D01*
Y-23155D01*
Y-23101D01*
Y-23047D01*
Y-22993D01*
Y-22939D01*
Y-22885D01*
Y-22831D01*
Y-22777D01*
Y-22723D01*
Y-22669D01*
Y-22615D01*
Y-22561D01*
Y-22506D01*
Y-22452D01*
Y-22398D01*
Y-22344D01*
Y-22290D01*
Y-22236D01*
Y-22182D01*
Y-22128D01*
Y-22074D01*
Y-22020D01*
Y-21966D01*
Y-21912D01*
Y-21858D01*
Y-21804D01*
Y-21750D01*
Y-21696D01*
Y-21642D01*
Y-21587D01*
Y-21533D01*
Y-21479D01*
Y-21425D01*
Y-21371D01*
Y-21356D01*
X377164Y-21355D01*
X377161Y-21348D01*
X377141Y-21309D01*
X377095Y-21286D01*
X377094Y-21285D01*
D02*
G37*
G36*
X372769D02*
X365099D01*
Y-21317D01*
Y-21371D01*
Y-21425D01*
Y-21479D01*
Y-21533D01*
Y-21587D01*
Y-21642D01*
Y-21696D01*
Y-21750D01*
Y-21804D01*
Y-21858D01*
Y-21912D01*
Y-21966D01*
Y-22020D01*
Y-22074D01*
Y-22128D01*
Y-22182D01*
Y-22236D01*
Y-22290D01*
Y-22344D01*
Y-22398D01*
Y-22452D01*
Y-22506D01*
Y-22561D01*
Y-22615D01*
Y-22669D01*
Y-22723D01*
Y-22777D01*
Y-22831D01*
Y-22885D01*
Y-22939D01*
Y-22993D01*
Y-23047D01*
Y-23101D01*
Y-23155D01*
Y-23209D01*
Y-23263D01*
Y-23317D01*
Y-23371D01*
Y-23395D01*
X365115Y-23403D01*
X365116Y-23403D01*
X365672D01*
X365724Y-23407D01*
X365775Y-23417D01*
X365825Y-23434D01*
X365872Y-23457D01*
X365916Y-23486D01*
X365955Y-23520D01*
X365990Y-23560D01*
X366019Y-23604D01*
X366042Y-23651D01*
X366059Y-23700D01*
X366069Y-23752D01*
X366073Y-23804D01*
Y-23858D01*
Y-23912D01*
Y-23966D01*
Y-24020D01*
Y-24074D01*
Y-24128D01*
Y-24182D01*
Y-24237D01*
Y-24291D01*
Y-24345D01*
Y-24399D01*
Y-24453D01*
Y-24507D01*
Y-24561D01*
Y-24615D01*
Y-24669D01*
Y-24723D01*
Y-24777D01*
Y-24831D01*
Y-24885D01*
Y-24939D01*
Y-24993D01*
Y-25047D01*
Y-25102D01*
Y-25155D01*
Y-25210D01*
Y-25264D01*
Y-25318D01*
Y-25372D01*
Y-25426D01*
Y-25480D01*
Y-25534D01*
Y-25588D01*
Y-25642D01*
Y-25696D01*
Y-25750D01*
Y-25804D01*
Y-25858D01*
Y-25912D01*
Y-25967D01*
Y-26021D01*
Y-26075D01*
Y-26129D01*
Y-26183D01*
Y-26237D01*
Y-26291D01*
Y-26345D01*
Y-26399D01*
Y-26453D01*
Y-26507D01*
Y-26561D01*
Y-26615D01*
Y-26669D01*
Y-26723D01*
Y-26777D01*
Y-26831D01*
Y-26886D01*
Y-26940D01*
Y-26994D01*
Y-27048D01*
Y-27102D01*
Y-27156D01*
Y-27210D01*
Y-27264D01*
Y-27318D01*
Y-27372D01*
Y-27426D01*
Y-27480D01*
Y-27534D01*
Y-27588D01*
Y-27642D01*
Y-27696D01*
Y-27751D01*
Y-27805D01*
Y-27859D01*
Y-27913D01*
Y-27967D01*
Y-28021D01*
Y-28075D01*
Y-28129D01*
Y-28183D01*
Y-28237D01*
Y-28291D01*
Y-28345D01*
Y-28399D01*
Y-28453D01*
Y-28507D01*
Y-28561D01*
Y-28615D01*
Y-28670D01*
Y-28724D01*
Y-28778D01*
Y-28832D01*
Y-28886D01*
Y-28940D01*
Y-28994D01*
Y-29048D01*
Y-29102D01*
Y-29156D01*
Y-29210D01*
Y-29264D01*
Y-29318D01*
Y-29372D01*
Y-29426D01*
Y-29480D01*
Y-29535D01*
Y-29589D01*
Y-29643D01*
Y-29697D01*
Y-29751D01*
Y-29805D01*
Y-29859D01*
Y-29913D01*
Y-29967D01*
Y-30021D01*
Y-30075D01*
Y-30129D01*
Y-30183D01*
Y-30237D01*
Y-30291D01*
Y-30345D01*
Y-30400D01*
Y-30454D01*
Y-30508D01*
Y-30562D01*
Y-30616D01*
Y-30670D01*
Y-30724D01*
Y-30778D01*
Y-30832D01*
Y-30886D01*
Y-30940D01*
Y-30994D01*
Y-31048D01*
Y-31102D01*
Y-31156D01*
Y-31211D01*
Y-31265D01*
Y-31319D01*
Y-31373D01*
Y-31427D01*
Y-31481D01*
Y-31535D01*
Y-31589D01*
Y-31643D01*
Y-31697D01*
Y-31751D01*
Y-31805D01*
Y-31859D01*
Y-31913D01*
Y-31967D01*
Y-32021D01*
Y-32076D01*
Y-32129D01*
Y-32184D01*
D01*
Y-32238D01*
Y-32269D01*
X368012D01*
X368012Y-32269D01*
X368022Y-32264D01*
X368028Y-32254D01*
X368028Y-32253D01*
Y-32238D01*
Y-32184D01*
D01*
Y-32129D01*
Y-32076D01*
Y-32021D01*
Y-31967D01*
Y-31913D01*
Y-31859D01*
Y-31805D01*
Y-31751D01*
Y-31697D01*
Y-31643D01*
Y-31589D01*
Y-31535D01*
Y-31481D01*
Y-31427D01*
Y-31373D01*
Y-31319D01*
Y-31265D01*
Y-31211D01*
Y-31156D01*
Y-31102D01*
Y-31048D01*
Y-30994D01*
Y-30940D01*
Y-30886D01*
Y-30832D01*
Y-30778D01*
Y-30724D01*
Y-30670D01*
Y-30616D01*
Y-30562D01*
Y-30508D01*
Y-30454D01*
Y-30400D01*
Y-30345D01*
Y-30291D01*
Y-30237D01*
Y-30183D01*
Y-30129D01*
Y-30075D01*
Y-30021D01*
Y-29967D01*
Y-29913D01*
Y-29859D01*
Y-29805D01*
Y-29751D01*
Y-29697D01*
Y-29643D01*
Y-29589D01*
Y-29535D01*
Y-29480D01*
Y-29426D01*
Y-29372D01*
Y-29318D01*
Y-29264D01*
Y-29210D01*
Y-29156D01*
Y-29102D01*
Y-29048D01*
Y-28994D01*
Y-28940D01*
Y-28886D01*
Y-28832D01*
Y-28778D01*
Y-28724D01*
Y-28670D01*
Y-28615D01*
Y-28561D01*
Y-28507D01*
Y-28453D01*
Y-28399D01*
Y-28345D01*
Y-28291D01*
Y-28237D01*
Y-28183D01*
Y-28129D01*
Y-28075D01*
Y-28021D01*
Y-27967D01*
Y-27913D01*
Y-27859D01*
Y-27805D01*
Y-27751D01*
Y-27696D01*
Y-27642D01*
Y-27588D01*
Y-27534D01*
Y-27480D01*
Y-27426D01*
Y-27372D01*
Y-27318D01*
Y-27264D01*
Y-27210D01*
Y-27156D01*
Y-27102D01*
Y-27048D01*
Y-26994D01*
Y-26940D01*
Y-26886D01*
Y-26831D01*
Y-26777D01*
Y-26723D01*
Y-26669D01*
Y-26615D01*
Y-26561D01*
Y-26507D01*
Y-26453D01*
Y-26399D01*
Y-26345D01*
Y-26291D01*
Y-26237D01*
Y-26183D01*
Y-26129D01*
Y-26075D01*
Y-26021D01*
Y-25967D01*
Y-25912D01*
Y-25858D01*
Y-25804D01*
Y-25750D01*
Y-25696D01*
Y-25642D01*
Y-25588D01*
Y-25534D01*
Y-25480D01*
Y-25426D01*
Y-25372D01*
Y-25318D01*
Y-25264D01*
Y-25210D01*
Y-25155D01*
Y-25102D01*
Y-25047D01*
Y-24993D01*
Y-24939D01*
Y-24885D01*
Y-24831D01*
Y-24777D01*
Y-24723D01*
Y-24669D01*
Y-24615D01*
Y-24561D01*
Y-24507D01*
Y-24453D01*
Y-24399D01*
Y-24345D01*
Y-24291D01*
Y-24237D01*
Y-24182D01*
Y-24128D01*
Y-24074D01*
Y-24020D01*
Y-23966D01*
Y-23912D01*
Y-23858D01*
Y-23804D01*
X368031Y-23752D01*
X368042Y-23700D01*
X368058Y-23651D01*
X368082Y-23604D01*
X368111Y-23560D01*
X368145Y-23520D01*
X368185Y-23486D01*
X368228Y-23457D01*
X368275Y-23434D01*
X368325Y-23417D01*
X368376Y-23407D01*
X368429Y-23403D01*
X370267D01*
X370319Y-23407D01*
X370371Y-23417D01*
X370420Y-23434D01*
X370467Y-23457D01*
X370511Y-23486D01*
X370550Y-23520D01*
X370585Y-23560D01*
X370614Y-23604D01*
X370637Y-23651D01*
X370654Y-23700D01*
X370664Y-23752D01*
X370668Y-23804D01*
Y-23858D01*
Y-23912D01*
Y-23966D01*
Y-24020D01*
Y-24074D01*
Y-24128D01*
Y-24182D01*
Y-24237D01*
Y-24291D01*
Y-24345D01*
Y-24399D01*
Y-24453D01*
Y-24507D01*
Y-24561D01*
Y-24615D01*
Y-24669D01*
Y-24723D01*
Y-24777D01*
Y-24831D01*
Y-24885D01*
Y-24939D01*
Y-24993D01*
Y-25047D01*
Y-25102D01*
Y-25155D01*
Y-25210D01*
Y-25264D01*
Y-25318D01*
Y-25372D01*
Y-25426D01*
Y-25480D01*
Y-25534D01*
Y-25588D01*
Y-25642D01*
Y-25696D01*
Y-25750D01*
Y-25804D01*
Y-25858D01*
Y-25912D01*
Y-25967D01*
Y-26021D01*
Y-26075D01*
Y-26129D01*
Y-26183D01*
Y-26237D01*
Y-26291D01*
Y-26345D01*
Y-26399D01*
Y-26453D01*
Y-26507D01*
Y-26561D01*
Y-26615D01*
Y-26669D01*
Y-26723D01*
Y-26777D01*
Y-26831D01*
Y-26886D01*
Y-26940D01*
Y-26994D01*
Y-27048D01*
Y-27102D01*
Y-27156D01*
Y-27210D01*
Y-27264D01*
Y-27318D01*
Y-27372D01*
Y-27426D01*
Y-27480D01*
Y-27534D01*
Y-27588D01*
Y-27642D01*
Y-27696D01*
Y-27751D01*
Y-27805D01*
Y-27859D01*
Y-27913D01*
Y-27967D01*
Y-28021D01*
Y-28075D01*
Y-28129D01*
Y-28183D01*
Y-28237D01*
Y-28291D01*
Y-28345D01*
Y-28399D01*
Y-28453D01*
Y-28507D01*
Y-28561D01*
Y-28615D01*
Y-28670D01*
Y-28724D01*
Y-28778D01*
Y-28832D01*
Y-28886D01*
Y-28940D01*
Y-28994D01*
Y-29048D01*
Y-29102D01*
Y-29156D01*
Y-29210D01*
Y-29264D01*
Y-29318D01*
Y-29372D01*
Y-29426D01*
Y-29480D01*
Y-29535D01*
Y-29589D01*
Y-29643D01*
Y-29697D01*
Y-29751D01*
Y-29805D01*
Y-29859D01*
Y-29913D01*
Y-29967D01*
Y-30021D01*
Y-30075D01*
Y-30129D01*
Y-30183D01*
Y-30237D01*
Y-30291D01*
Y-30345D01*
Y-30400D01*
Y-30454D01*
Y-30508D01*
Y-30562D01*
Y-30616D01*
Y-30670D01*
Y-30724D01*
Y-30778D01*
Y-30832D01*
Y-30886D01*
Y-30940D01*
Y-30994D01*
Y-31048D01*
Y-31102D01*
Y-31156D01*
Y-31211D01*
Y-31265D01*
Y-31319D01*
Y-31373D01*
Y-31427D01*
Y-31481D01*
Y-31535D01*
Y-31589D01*
Y-31643D01*
Y-31697D01*
Y-31751D01*
Y-31805D01*
Y-31859D01*
Y-31913D01*
Y-31967D01*
Y-32021D01*
Y-32076D01*
Y-32129D01*
Y-32184D01*
D01*
Y-32238D01*
Y-32253D01*
X370668Y-32254D01*
X370676Y-32269D01*
X372839D01*
Y-32238D01*
Y-32184D01*
D01*
Y-32129D01*
Y-32076D01*
Y-32021D01*
Y-31967D01*
Y-31913D01*
Y-31859D01*
Y-31805D01*
Y-31751D01*
Y-31697D01*
Y-31643D01*
Y-31589D01*
Y-31535D01*
Y-31481D01*
Y-31427D01*
Y-31373D01*
Y-31319D01*
Y-31265D01*
Y-31211D01*
Y-31156D01*
Y-31102D01*
Y-31048D01*
Y-30994D01*
Y-30940D01*
Y-30886D01*
Y-30832D01*
Y-30778D01*
Y-30724D01*
Y-30670D01*
Y-30616D01*
Y-30562D01*
Y-30508D01*
Y-30454D01*
Y-30400D01*
Y-30345D01*
Y-30291D01*
Y-30237D01*
Y-30183D01*
Y-30129D01*
Y-30075D01*
Y-30021D01*
Y-29967D01*
Y-29913D01*
Y-29859D01*
Y-29805D01*
Y-29751D01*
Y-29697D01*
Y-29643D01*
Y-29589D01*
Y-29535D01*
Y-29480D01*
Y-29426D01*
Y-29372D01*
Y-29318D01*
Y-29264D01*
Y-29210D01*
Y-29156D01*
Y-29102D01*
Y-29048D01*
Y-28994D01*
Y-28940D01*
Y-28886D01*
Y-28832D01*
Y-28778D01*
Y-28724D01*
Y-28670D01*
Y-28615D01*
Y-28561D01*
Y-28507D01*
Y-28453D01*
Y-28399D01*
Y-28345D01*
Y-28291D01*
Y-28237D01*
Y-28183D01*
Y-28129D01*
Y-28075D01*
Y-28021D01*
Y-27967D01*
Y-27913D01*
Y-27859D01*
Y-27805D01*
Y-27751D01*
Y-27696D01*
Y-27642D01*
Y-27588D01*
Y-27534D01*
Y-27480D01*
Y-27426D01*
Y-27372D01*
Y-27318D01*
Y-27264D01*
Y-27210D01*
Y-27156D01*
Y-27102D01*
Y-27048D01*
Y-26994D01*
Y-26940D01*
Y-26886D01*
Y-26831D01*
Y-26777D01*
Y-26723D01*
Y-26669D01*
Y-26615D01*
Y-26561D01*
Y-26507D01*
Y-26453D01*
Y-26399D01*
Y-26345D01*
Y-26291D01*
Y-26237D01*
Y-26183D01*
Y-26129D01*
Y-26075D01*
Y-26021D01*
Y-25967D01*
Y-25912D01*
Y-25858D01*
Y-25804D01*
Y-25750D01*
Y-25696D01*
Y-25642D01*
Y-25588D01*
Y-25534D01*
Y-25480D01*
Y-25426D01*
Y-25372D01*
Y-25318D01*
Y-25264D01*
Y-25210D01*
Y-25155D01*
Y-25102D01*
Y-25047D01*
Y-24993D01*
Y-24939D01*
Y-24885D01*
Y-24831D01*
Y-24777D01*
Y-24723D01*
Y-24669D01*
Y-24615D01*
Y-24561D01*
Y-24507D01*
Y-24453D01*
Y-24399D01*
Y-24345D01*
Y-24291D01*
Y-24237D01*
Y-24182D01*
Y-24128D01*
Y-24074D01*
Y-24020D01*
Y-23966D01*
Y-23912D01*
Y-23858D01*
Y-23804D01*
Y-23750D01*
Y-23696D01*
Y-23642D01*
Y-23588D01*
Y-23534D01*
Y-23480D01*
Y-23426D01*
Y-23371D01*
Y-23317D01*
Y-23263D01*
Y-23209D01*
Y-23155D01*
Y-23101D01*
Y-23047D01*
Y-22993D01*
Y-22939D01*
Y-22885D01*
Y-22831D01*
Y-22777D01*
Y-22723D01*
Y-22669D01*
Y-22615D01*
Y-22561D01*
Y-22506D01*
Y-22452D01*
Y-22398D01*
Y-22344D01*
Y-22290D01*
Y-22236D01*
Y-22182D01*
Y-22128D01*
Y-22074D01*
Y-22020D01*
Y-21966D01*
Y-21912D01*
Y-21858D01*
Y-21804D01*
Y-21750D01*
Y-21696D01*
Y-21642D01*
Y-21587D01*
Y-21533D01*
Y-21479D01*
Y-21425D01*
Y-21371D01*
Y-21317D01*
Y-21317D01*
X372817Y-21309D01*
X372770Y-21286D01*
X372769Y-21285D01*
D02*
G37*
G36*
X363379Y-14852D02*
X363007D01*
X363007Y-14852D01*
X362960Y-14876D01*
X362910Y-14893D01*
X362859Y-14903D01*
X362806Y-14906D01*
X362791D01*
X362791Y-14907D01*
X362744Y-14930D01*
X362724Y-14936D01*
X362717Y-14944D01*
X362711Y-14951D01*
X362683Y-14976D01*
X362667Y-14994D01*
X362657Y-15005D01*
X362629Y-15030D01*
X362613Y-15048D01*
X362603Y-15059D01*
X362575Y-15084D01*
X362549Y-15113D01*
X362520Y-15138D01*
X362495Y-15167D01*
X362466Y-15192D01*
X362441Y-15221D01*
X362416Y-15243D01*
X362412Y-15247D01*
X362387Y-15275D01*
X362358Y-15301D01*
X362333Y-15329D01*
X362304Y-15355D01*
X362279Y-15383D01*
X362250Y-15409D01*
X362225Y-15438D01*
X362200Y-15459D01*
X362196Y-15463D01*
X362171Y-15492D01*
X362142Y-15517D01*
X362117Y-15546D01*
X362088Y-15571D01*
X362076Y-15585D01*
X362063Y-15600D01*
X362034Y-15625D01*
X362009Y-15654D01*
X361980Y-15679D01*
X361955Y-15708D01*
X361926Y-15733D01*
X361900Y-15762D01*
X361872Y-15787D01*
X361846Y-15816D01*
X361818Y-15841D01*
X361803Y-15858D01*
X361792Y-15870D01*
X361764Y-15895D01*
X361738Y-15924D01*
X361709Y-15949D01*
X361684Y-15978D01*
X361655Y-16003D01*
X361630Y-16032D01*
X361605Y-16054D01*
X361601Y-16058D01*
X361576Y-16086D01*
X361547Y-16112D01*
X361532Y-16129D01*
X361522Y-16140D01*
X361493Y-16165D01*
X361481Y-16180D01*
X361468Y-16194D01*
X361439Y-16220D01*
X361414Y-16248D01*
X361385Y-16274D01*
X361360Y-16303D01*
X361345Y-16315D01*
X361339Y-16335D01*
X361315Y-16382D01*
X361315Y-16382D01*
Y-16398D01*
X361312Y-16450D01*
X361301Y-16501D01*
X361285Y-16551D01*
X361261Y-16598D01*
X361261Y-16598D01*
Y-16614D01*
Y-16668D01*
Y-16722D01*
Y-16776D01*
Y-16830D01*
Y-16884D01*
Y-16938D01*
Y-16992D01*
Y-17046D01*
Y-17100D01*
Y-17154D01*
Y-17208D01*
Y-17263D01*
Y-17317D01*
Y-17371D01*
Y-17425D01*
Y-17479D01*
Y-17533D01*
Y-17587D01*
Y-17641D01*
Y-17695D01*
Y-17749D01*
Y-17803D01*
Y-17857D01*
Y-17911D01*
Y-17965D01*
Y-18019D01*
Y-18073D01*
Y-18127D01*
Y-18181D01*
Y-18236D01*
Y-18290D01*
Y-18344D01*
Y-18398D01*
Y-18452D01*
Y-18506D01*
Y-18560D01*
Y-18614D01*
Y-18668D01*
Y-18722D01*
Y-18776D01*
Y-18830D01*
Y-18884D01*
Y-18938D01*
Y-18993D01*
Y-19047D01*
Y-19101D01*
Y-19155D01*
Y-19209D01*
Y-19263D01*
Y-19317D01*
Y-19371D01*
Y-19425D01*
Y-19479D01*
Y-19533D01*
Y-19587D01*
Y-19641D01*
Y-19695D01*
Y-19749D01*
Y-19803D01*
Y-19858D01*
Y-19911D01*
Y-19966D01*
Y-20020D01*
Y-20074D01*
Y-20128D01*
Y-20182D01*
Y-20236D01*
Y-20290D01*
Y-20344D01*
Y-20398D01*
Y-20452D01*
Y-20506D01*
Y-20560D01*
Y-20614D01*
Y-20668D01*
Y-20722D01*
Y-20776D01*
Y-20831D01*
Y-20885D01*
Y-20939D01*
Y-20993D01*
Y-21047D01*
Y-21101D01*
Y-21155D01*
Y-21209D01*
Y-21263D01*
Y-21317D01*
Y-21371D01*
Y-21425D01*
Y-21479D01*
Y-21533D01*
Y-21587D01*
Y-21642D01*
Y-21696D01*
Y-21750D01*
Y-21804D01*
Y-21858D01*
Y-21912D01*
Y-21966D01*
Y-22020D01*
Y-22074D01*
Y-22128D01*
Y-22182D01*
Y-22236D01*
Y-22290D01*
Y-22344D01*
Y-22398D01*
Y-22452D01*
Y-22506D01*
Y-22561D01*
Y-22615D01*
Y-22669D01*
Y-22723D01*
Y-22777D01*
Y-22831D01*
Y-22885D01*
Y-22939D01*
Y-22993D01*
Y-23047D01*
Y-23101D01*
Y-23155D01*
Y-23209D01*
Y-23263D01*
Y-23317D01*
Y-23371D01*
Y-23426D01*
Y-23480D01*
Y-23534D01*
Y-23588D01*
Y-23642D01*
Y-23696D01*
Y-23750D01*
Y-23804D01*
Y-23858D01*
Y-23912D01*
Y-23966D01*
Y-24020D01*
Y-24074D01*
Y-24128D01*
Y-24182D01*
Y-24237D01*
Y-24291D01*
Y-24345D01*
Y-24399D01*
Y-24453D01*
Y-24507D01*
Y-24561D01*
Y-24615D01*
Y-24669D01*
Y-24723D01*
Y-24777D01*
Y-24831D01*
Y-24885D01*
Y-24939D01*
Y-24993D01*
Y-25047D01*
Y-25102D01*
Y-25155D01*
Y-25210D01*
Y-25264D01*
Y-25318D01*
Y-25372D01*
Y-25426D01*
Y-25480D01*
Y-25534D01*
Y-25588D01*
Y-25642D01*
Y-25696D01*
Y-25750D01*
Y-25804D01*
Y-25858D01*
Y-25912D01*
Y-25967D01*
Y-26021D01*
Y-26075D01*
Y-26129D01*
Y-26183D01*
Y-26237D01*
Y-26291D01*
Y-26345D01*
Y-26399D01*
Y-26453D01*
Y-26507D01*
Y-26561D01*
Y-26615D01*
Y-26669D01*
Y-26723D01*
Y-26777D01*
Y-26831D01*
Y-26886D01*
Y-26940D01*
Y-26994D01*
Y-27048D01*
Y-27102D01*
Y-27156D01*
Y-27210D01*
Y-27264D01*
Y-27318D01*
Y-27372D01*
Y-27426D01*
Y-27480D01*
Y-27534D01*
Y-27588D01*
Y-27642D01*
Y-27696D01*
Y-27751D01*
Y-27805D01*
Y-27859D01*
Y-27913D01*
Y-27967D01*
Y-28021D01*
Y-28075D01*
Y-28129D01*
Y-28183D01*
Y-28237D01*
Y-28291D01*
Y-28345D01*
Y-28399D01*
Y-28453D01*
Y-28507D01*
Y-28561D01*
Y-28615D01*
Y-28670D01*
Y-28724D01*
Y-28778D01*
Y-28832D01*
Y-28886D01*
Y-28940D01*
Y-28994D01*
Y-29048D01*
Y-29102D01*
Y-29156D01*
Y-29210D01*
Y-29264D01*
Y-29318D01*
Y-29372D01*
Y-29426D01*
Y-29480D01*
Y-29535D01*
Y-29589D01*
Y-29643D01*
Y-29697D01*
Y-29751D01*
Y-29805D01*
Y-29859D01*
Y-29913D01*
Y-29967D01*
Y-30021D01*
Y-30075D01*
Y-30129D01*
Y-30183D01*
Y-30237D01*
Y-30291D01*
Y-30345D01*
Y-30400D01*
Y-30454D01*
Y-30508D01*
Y-30562D01*
Y-30616D01*
Y-30670D01*
Y-30724D01*
Y-30778D01*
Y-30832D01*
Y-30886D01*
Y-30940D01*
Y-30994D01*
Y-31048D01*
Y-31102D01*
Y-31156D01*
Y-31211D01*
Y-31265D01*
Y-31319D01*
Y-31373D01*
Y-31427D01*
Y-31481D01*
Y-31535D01*
Y-31589D01*
Y-31643D01*
Y-31697D01*
Y-31751D01*
Y-31805D01*
Y-31859D01*
Y-31913D01*
Y-31967D01*
Y-32021D01*
Y-32076D01*
Y-32129D01*
Y-32184D01*
D01*
Y-32238D01*
Y-32292D01*
Y-32346D01*
Y-32400D01*
Y-32454D01*
Y-32508D01*
Y-32562D01*
Y-32616D01*
Y-32670D01*
Y-32724D01*
Y-32778D01*
Y-32832D01*
Y-32886D01*
Y-32941D01*
Y-32994D01*
Y-33010D01*
X361261Y-33010D01*
X361285Y-33057D01*
X361301Y-33107D01*
X361312Y-33158D01*
X361315Y-33211D01*
Y-33226D01*
X361315Y-33227D01*
X361339Y-33274D01*
X361349Y-33304D01*
X361369Y-33335D01*
X361393Y-33382D01*
X361403Y-33412D01*
X361418Y-33435D01*
X361424Y-33443D01*
X361447Y-33490D01*
X361453Y-33509D01*
X361468Y-33522D01*
X361503Y-33561D01*
X361532Y-33605D01*
X361555Y-33652D01*
X361561Y-33671D01*
X361576Y-33684D01*
X361601Y-33713D01*
X361630Y-33738D01*
X361655Y-33767D01*
X361684Y-33792D01*
X361709Y-33821D01*
X361738Y-33846D01*
X361764Y-33875D01*
X361792Y-33900D01*
X361818Y-33929D01*
X361846Y-33955D01*
X361872Y-33983D01*
X361884Y-33994D01*
X361900Y-34009D01*
X361926Y-34037D01*
X361955Y-34063D01*
X361980Y-34091D01*
X362001Y-34110D01*
X362009Y-34117D01*
X362034Y-34146D01*
X362060Y-34168D01*
X362063Y-34171D01*
X362088Y-34200D01*
X362114Y-34222D01*
X362117Y-34225D01*
X362142Y-34254D01*
X362154Y-34264D01*
X362171Y-34279D01*
X362196Y-34308D01*
X362225Y-34333D01*
X362250Y-34362D01*
X362279Y-34387D01*
X362304Y-34416D01*
X362333Y-34441D01*
X362358Y-34470D01*
X362387Y-34495D01*
X362412Y-34524D01*
X362424Y-34534D01*
X362441Y-34549D01*
X362466Y-34578D01*
X362495Y-34603D01*
X362520Y-34632D01*
X362549Y-34657D01*
X362575Y-34686D01*
X362603Y-34711D01*
X362629Y-34740D01*
X362654Y-34763D01*
X362657Y-34765D01*
X362683Y-34794D01*
X362711Y-34819D01*
X362737Y-34848D01*
X362766Y-34874D01*
X362791Y-34902D01*
X362820Y-34928D01*
X362845Y-34956D01*
X362874Y-34982D01*
X362899Y-35010D01*
X362928Y-35036D01*
X362953Y-35065D01*
X362982Y-35090D01*
X363007Y-35119D01*
X363036Y-35144D01*
X363049Y-35159D01*
X363057Y-35161D01*
X363068Y-35165D01*
X363115Y-35188D01*
X363159Y-35217D01*
X363198Y-35252D01*
X363223Y-35281D01*
X363252Y-35306D01*
X363277Y-35335D01*
X363306Y-35360D01*
X363331Y-35389D01*
X363360Y-35414D01*
X363385Y-35443D01*
X363414Y-35468D01*
X363439Y-35497D01*
X363448Y-35504D01*
X363468Y-35522D01*
X363493Y-35551D01*
X363522Y-35576D01*
X363548Y-35605D01*
X363576Y-35630D01*
X363602Y-35659D01*
X363631Y-35684D01*
X363656Y-35713D01*
X363685Y-35739D01*
X363710Y-35767D01*
X363736Y-35790D01*
X363739Y-35793D01*
X363764Y-35821D01*
X363793Y-35847D01*
X363818Y-35875D01*
X363847Y-35901D01*
X363872Y-35930D01*
X363901Y-35955D01*
X363926Y-35984D01*
X363955Y-36009D01*
X363980Y-36038D01*
X364009Y-36063D01*
X364034Y-36092D01*
X364063Y-36117D01*
X364088Y-36146D01*
X364117Y-36171D01*
X364142Y-36200D01*
X364171Y-36225D01*
X364196Y-36254D01*
X364225Y-36279D01*
X364250Y-36308D01*
X364279Y-36333D01*
X364304Y-36362D01*
X364333Y-36387D01*
X364359Y-36416D01*
X364387Y-36441D01*
X364413Y-36470D01*
X364441Y-36495D01*
X364467Y-36524D01*
X364495Y-36549D01*
X364521Y-36578D01*
X364549Y-36604D01*
X364575Y-36632D01*
X364604Y-36658D01*
X364629Y-36686D01*
X364658Y-36712D01*
X364683Y-36740D01*
X364712Y-36766D01*
X364737Y-36794D01*
X364766Y-36820D01*
X364791Y-36849D01*
X364820Y-36874D01*
X364845Y-36903D01*
X364874Y-36928D01*
X364899Y-36957D01*
X364928Y-36982D01*
X364953Y-37011D01*
X364982Y-37036D01*
X365007Y-37065D01*
X365036Y-37090D01*
X365061Y-37119D01*
X365090Y-37144D01*
X365115Y-37173D01*
X365144Y-37198D01*
X365170Y-37227D01*
X365198Y-37252D01*
X365224Y-37281D01*
X365252Y-37306D01*
X365278Y-37335D01*
X365286Y-37342D01*
X365306Y-37360D01*
X365332Y-37389D01*
X365360Y-37415D01*
X365386Y-37443D01*
X365415Y-37468D01*
X365440Y-37497D01*
X365469Y-37523D01*
X365494Y-37551D01*
X365523Y-37577D01*
X365548Y-37606D01*
X365577Y-37631D01*
X365602Y-37659D01*
X365628Y-37682D01*
X365631Y-37685D01*
X365656Y-37714D01*
X365685Y-37739D01*
X365710Y-37768D01*
X365739Y-37793D01*
X365764Y-37822D01*
X365793Y-37847D01*
X365818Y-37876D01*
X365832Y-37888D01*
X365847Y-37901D01*
X365872Y-37930D01*
X365898Y-37952D01*
X365901Y-37955D01*
X365926Y-37984D01*
X365955Y-38009D01*
X365980Y-38038D01*
X366009Y-38063D01*
X366035Y-38092D01*
X366063Y-38117D01*
X366089Y-38146D01*
X366117Y-38171D01*
X366143Y-38200D01*
X366171Y-38225D01*
X366197Y-38254D01*
X366226Y-38280D01*
X366251Y-38308D01*
X366280Y-38333D01*
X366305Y-38362D01*
X366334Y-38388D01*
X366359Y-38416D01*
X366377Y-38432D01*
X366388Y-38442D01*
X366413Y-38471D01*
X366439Y-38493D01*
X366442Y-38496D01*
X366467Y-38524D01*
X366496Y-38550D01*
X366521Y-38579D01*
X366550Y-38604D01*
X366575Y-38633D01*
X366604Y-38658D01*
X366629Y-38687D01*
X366643Y-38699D01*
X366658Y-38712D01*
X366683Y-38741D01*
X366709Y-38763D01*
X366712Y-38766D01*
X366737Y-38795D01*
X366766Y-38820D01*
X366791Y-38849D01*
X366820Y-38874D01*
X366845Y-38903D01*
X366874Y-38928D01*
X366899Y-38957D01*
X366928Y-38982D01*
X366953Y-39011D01*
X366982Y-39036D01*
X367008Y-39065D01*
X367036Y-39090D01*
X367062Y-39119D01*
X367091Y-39145D01*
X367116Y-39173D01*
X367144Y-39198D01*
X367170Y-39227D01*
X367199Y-39253D01*
X367224Y-39281D01*
X367253Y-39307D01*
X367278Y-39335D01*
X367307Y-39361D01*
X367332Y-39390D01*
X367361Y-39415D01*
X367386Y-39444D01*
X367415Y-39469D01*
X367440Y-39498D01*
X367469Y-39523D01*
X367494Y-39552D01*
X367523Y-39577D01*
X367548Y-39606D01*
X367574Y-39628D01*
X367577Y-39631D01*
X367602Y-39660D01*
X367631Y-39685D01*
X367644Y-39700D01*
X367663Y-39706D01*
X367710Y-39729D01*
X367754Y-39759D01*
X367793Y-39793D01*
X367818Y-39822D01*
X367847Y-39847D01*
X367873Y-39876D01*
X367901Y-39901D01*
X367927Y-39930D01*
X367955Y-39955D01*
X367981Y-39984D01*
X368006Y-40007D01*
X368009Y-40009D01*
X368035Y-40038D01*
X368064Y-40064D01*
X368089Y-40092D01*
X368118Y-40118D01*
X368143Y-40146D01*
X368172Y-40172D01*
X368197Y-40200D01*
X368226Y-40226D01*
X368251Y-40255D01*
X368280Y-40280D01*
X368305Y-40309D01*
X368334Y-40334D01*
X368359Y-40363D01*
X368388Y-40388D01*
X368413Y-40417D01*
X368442Y-40442D01*
X368467Y-40471D01*
X368496Y-40496D01*
X368521Y-40525D01*
X368550Y-40550D01*
X368575Y-40579D01*
X368604Y-40604D01*
X368629Y-40633D01*
X368655Y-40655D01*
X368658Y-40658D01*
X368684Y-40687D01*
X368712Y-40712D01*
X368738Y-40741D01*
X368766Y-40766D01*
X368792Y-40795D01*
X368807Y-40809D01*
X368823Y-40795D01*
X368848Y-40766D01*
X368877Y-40741D01*
X368902Y-40712D01*
X368931Y-40687D01*
X368956Y-40658D01*
X368971Y-40645D01*
X368978Y-40626D01*
X369001Y-40579D01*
X369030Y-40535D01*
X369064Y-40496D01*
X369079Y-40483D01*
X369086Y-40464D01*
X369109Y-40417D01*
X369138Y-40373D01*
X369163Y-40344D01*
Y-40293D01*
Y-40239D01*
Y-40185D01*
Y-40131D01*
Y-40077D01*
Y-40023D01*
Y-39968D01*
Y-39915D01*
Y-39860D01*
Y-39806D01*
Y-39752D01*
Y-39698D01*
Y-39644D01*
Y-39590D01*
Y-39536D01*
Y-39482D01*
Y-39428D01*
Y-39374D01*
Y-39320D01*
Y-39266D01*
Y-39212D01*
Y-39158D01*
Y-39103D01*
Y-39050D01*
Y-38995D01*
Y-38941D01*
Y-38887D01*
Y-38833D01*
Y-38779D01*
Y-38725D01*
Y-38671D01*
Y-38617D01*
Y-38563D01*
Y-38509D01*
Y-38455D01*
Y-38401D01*
Y-38347D01*
Y-38331D01*
X369163Y-38331D01*
X369140Y-38284D01*
X369138Y-38280D01*
X369129Y-38254D01*
X369109Y-38223D01*
X369086Y-38176D01*
X369081Y-38162D01*
X369079Y-38157D01*
X369064Y-38144D01*
X369030Y-38104D01*
X369001Y-38061D01*
X368978Y-38013D01*
X368971Y-37994D01*
X368956Y-37981D01*
X368931Y-37953D01*
X368902Y-37927D01*
X368877Y-37898D01*
X368873Y-37895D01*
X368848Y-37873D01*
X368830Y-37852D01*
X368823Y-37844D01*
X368794Y-37819D01*
X368769Y-37790D01*
X368740Y-37765D01*
X368715Y-37736D01*
X368686Y-37711D01*
X368661Y-37682D01*
X368657Y-37679D01*
X368632Y-37657D01*
X368607Y-37628D01*
X368578Y-37603D01*
X368553Y-37574D01*
X368524Y-37549D01*
X368499Y-37520D01*
X368470Y-37495D01*
X368444Y-37466D01*
X368416Y-37441D01*
X368390Y-37412D01*
X368362Y-37387D01*
X368336Y-37358D01*
X368308Y-37333D01*
X368282Y-37304D01*
X368253Y-37279D01*
X368241Y-37264D01*
X368221Y-37257D01*
X368174Y-37234D01*
X368131Y-37205D01*
X368091Y-37170D01*
X368066Y-37142D01*
X368037Y-37116D01*
X368012Y-37088D01*
X367983Y-37062D01*
X367958Y-37034D01*
X367929Y-37008D01*
X367904Y-36979D01*
X367875Y-36954D01*
X367850Y-36925D01*
X367821Y-36900D01*
X367796Y-36871D01*
X367767Y-36846D01*
X367742Y-36817D01*
X367713Y-36792D01*
X367688Y-36763D01*
X367659Y-36738D01*
X367634Y-36709D01*
X367605Y-36684D01*
X367580Y-36655D01*
X367551Y-36630D01*
X367525Y-36601D01*
X367497Y-36576D01*
X367472Y-36547D01*
X367443Y-36522D01*
X367430Y-36507D01*
X367417Y-36493D01*
X367389Y-36468D01*
X367363Y-36439D01*
X367335Y-36414D01*
X367309Y-36385D01*
X367280Y-36360D01*
X367255Y-36331D01*
X367226Y-36305D01*
X367201Y-36277D01*
X367172Y-36251D01*
X367147Y-36223D01*
X367118Y-36197D01*
X367093Y-36169D01*
X367064Y-36143D01*
X367039Y-36114D01*
X367010Y-36089D01*
X366985Y-36060D01*
X366956Y-36035D01*
X366931Y-36006D01*
X366902Y-35981D01*
X366877Y-35952D01*
X366848Y-35927D01*
X366823Y-35898D01*
X366794Y-35873D01*
X366769Y-35844D01*
X366740Y-35819D01*
X366715Y-35790D01*
X366686Y-35765D01*
X366660Y-35736D01*
X366632Y-35711D01*
X366606Y-35682D01*
X366578Y-35657D01*
X366552Y-35628D01*
X366524Y-35603D01*
X366498Y-35574D01*
X366484Y-35561D01*
X366470Y-35549D01*
X366444Y-35520D01*
X366440Y-35516D01*
X366415Y-35495D01*
X366397Y-35473D01*
X366390Y-35466D01*
X366361Y-35440D01*
X366336Y-35412D01*
X366307Y-35386D01*
X366282Y-35358D01*
X366253Y-35332D01*
X366228Y-35304D01*
X366199Y-35278D01*
X366174Y-35249D01*
X366145Y-35224D01*
X366120Y-35195D01*
X366091Y-35170D01*
X366066Y-35141D01*
X366037Y-35116D01*
X366012Y-35087D01*
X365983Y-35062D01*
X365958Y-35033D01*
X365929Y-35008D01*
X365904Y-34979D01*
X365875Y-34954D01*
X365849Y-34925D01*
X365821Y-34900D01*
X365808Y-34885D01*
X365795Y-34871D01*
X365767Y-34846D01*
X365741Y-34817D01*
X365713Y-34792D01*
X365687Y-34763D01*
X365659Y-34738D01*
X365633Y-34709D01*
X365630Y-34705D01*
X365604Y-34684D01*
X365579Y-34655D01*
X365550Y-34629D01*
X365525Y-34601D01*
X365496Y-34576D01*
X365471Y-34547D01*
X365442Y-34521D01*
X365417Y-34493D01*
X365388Y-34467D01*
X365363Y-34438D01*
X365359Y-34435D01*
X365334Y-34413D01*
X365309Y-34385D01*
X365280Y-34359D01*
X365255Y-34330D01*
X365226Y-34305D01*
X365201Y-34276D01*
X365172Y-34251D01*
X365147Y-34222D01*
X365118Y-34197D01*
X365093Y-34168D01*
X365089Y-34165D01*
X365064Y-34143D01*
X365039Y-34114D01*
X365010Y-34089D01*
X364984Y-34060D01*
X364956Y-34035D01*
X364931Y-34006D01*
X364919Y-33996D01*
X364902Y-33981D01*
X364876Y-33952D01*
X364848Y-33927D01*
X364822Y-33898D01*
X364794Y-33873D01*
X364768Y-33844D01*
X364739Y-33819D01*
X364714Y-33790D01*
X364685Y-33764D01*
X364660Y-33736D01*
X364631Y-33711D01*
X364606Y-33682D01*
X364577Y-33656D01*
X364564Y-33642D01*
X364545Y-33635D01*
X364498Y-33612D01*
X364455Y-33583D01*
X364415Y-33548D01*
X364390Y-33520D01*
X364361Y-33494D01*
X364336Y-33465D01*
X364307Y-33440D01*
X364282Y-33411D01*
X364274Y-33405D01*
X364253Y-33386D01*
X364228Y-33357D01*
X364199Y-33332D01*
X364174Y-33303D01*
X364145Y-33278D01*
X364120Y-33249D01*
X364091Y-33224D01*
X364066Y-33195D01*
X364037Y-33170D01*
X364012Y-33141D01*
X363983Y-33116D01*
X363957Y-33087D01*
X363929Y-33062D01*
X363903Y-33033D01*
X363875Y-33008D01*
X363849Y-32979D01*
X363820Y-32954D01*
X363795Y-32925D01*
X363766Y-32899D01*
X363741Y-32871D01*
X363741Y-32871D01*
X363712Y-32846D01*
X363701Y-32832D01*
X363687Y-32817D01*
X363658Y-32791D01*
X363639Y-32770D01*
X363633Y-32763D01*
X363604Y-32737D01*
X363579Y-32709D01*
X363550Y-32683D01*
X363525Y-32655D01*
X363496Y-32629D01*
X363461Y-32590D01*
X363432Y-32546D01*
X363409Y-32499D01*
X363392Y-32449D01*
X363382Y-32398D01*
X363379Y-32346D01*
Y-32292D01*
Y-32238D01*
Y-32184D01*
D01*
Y-32129D01*
Y-32076D01*
Y-32021D01*
Y-31967D01*
Y-31913D01*
Y-31859D01*
Y-31805D01*
Y-31751D01*
Y-31697D01*
Y-31643D01*
Y-31589D01*
Y-31535D01*
Y-31481D01*
Y-31427D01*
Y-31373D01*
Y-31319D01*
Y-31265D01*
Y-31211D01*
Y-31156D01*
Y-31102D01*
Y-31048D01*
Y-30994D01*
Y-30940D01*
Y-30886D01*
Y-30832D01*
Y-30778D01*
Y-30724D01*
Y-30670D01*
Y-30616D01*
Y-30562D01*
Y-30508D01*
Y-30454D01*
Y-30400D01*
Y-30345D01*
Y-30291D01*
Y-30237D01*
Y-30183D01*
Y-30129D01*
Y-30075D01*
Y-30021D01*
Y-29967D01*
Y-29913D01*
Y-29859D01*
Y-29805D01*
Y-29751D01*
Y-29697D01*
Y-29643D01*
Y-29589D01*
Y-29535D01*
Y-29480D01*
Y-29426D01*
Y-29372D01*
Y-29318D01*
Y-29264D01*
Y-29210D01*
Y-29156D01*
Y-29102D01*
Y-29048D01*
Y-28994D01*
Y-28940D01*
Y-28886D01*
Y-28832D01*
Y-28778D01*
Y-28724D01*
Y-28670D01*
Y-28615D01*
Y-28561D01*
Y-28507D01*
Y-28453D01*
Y-28399D01*
Y-28345D01*
Y-28291D01*
Y-28237D01*
Y-28183D01*
Y-28129D01*
Y-28075D01*
Y-28021D01*
Y-27967D01*
Y-27913D01*
Y-27859D01*
Y-27805D01*
Y-27751D01*
Y-27696D01*
Y-27642D01*
Y-27588D01*
Y-27534D01*
Y-27480D01*
Y-27426D01*
Y-27372D01*
Y-27318D01*
Y-27264D01*
Y-27210D01*
Y-27156D01*
Y-27102D01*
Y-27048D01*
Y-26994D01*
Y-26940D01*
Y-26886D01*
Y-26831D01*
Y-26777D01*
Y-26723D01*
Y-26669D01*
Y-26615D01*
Y-26561D01*
Y-26507D01*
Y-26453D01*
Y-26399D01*
Y-26345D01*
Y-26291D01*
Y-26237D01*
Y-26183D01*
Y-26129D01*
Y-26075D01*
Y-26021D01*
Y-25967D01*
Y-25912D01*
Y-25858D01*
Y-25804D01*
Y-25750D01*
Y-25696D01*
Y-25642D01*
Y-25588D01*
Y-25534D01*
Y-25480D01*
Y-25426D01*
Y-25372D01*
Y-25318D01*
Y-25264D01*
Y-25210D01*
Y-25155D01*
Y-25102D01*
Y-25047D01*
Y-24993D01*
Y-24939D01*
Y-24885D01*
Y-24831D01*
Y-24777D01*
Y-24723D01*
Y-24669D01*
Y-24615D01*
Y-24561D01*
Y-24507D01*
Y-24453D01*
Y-24399D01*
Y-24345D01*
Y-24291D01*
Y-24237D01*
Y-24182D01*
Y-24128D01*
Y-24074D01*
Y-24020D01*
Y-23966D01*
Y-23912D01*
Y-23858D01*
Y-23804D01*
Y-23750D01*
Y-23696D01*
Y-23642D01*
Y-23588D01*
Y-23534D01*
Y-23480D01*
Y-23426D01*
Y-23371D01*
Y-23317D01*
Y-23263D01*
Y-23209D01*
Y-23155D01*
Y-23101D01*
Y-23047D01*
Y-22993D01*
Y-22939D01*
Y-22885D01*
Y-22831D01*
Y-22777D01*
Y-22723D01*
Y-22669D01*
Y-22615D01*
Y-22561D01*
Y-22506D01*
Y-22452D01*
Y-22398D01*
Y-22344D01*
Y-22290D01*
Y-22236D01*
Y-22182D01*
Y-22128D01*
Y-22074D01*
Y-22020D01*
Y-21966D01*
Y-21912D01*
Y-21858D01*
Y-21804D01*
Y-21750D01*
Y-21696D01*
Y-21642D01*
Y-21587D01*
Y-21533D01*
Y-21479D01*
Y-21425D01*
Y-21371D01*
Y-21317D01*
Y-21263D01*
Y-21209D01*
Y-21155D01*
Y-21101D01*
Y-21047D01*
Y-20993D01*
Y-20939D01*
Y-20885D01*
Y-20831D01*
Y-20776D01*
Y-20722D01*
Y-20668D01*
Y-20614D01*
Y-20560D01*
Y-20506D01*
Y-20452D01*
Y-20398D01*
Y-20344D01*
Y-20290D01*
Y-20236D01*
Y-20182D01*
Y-20128D01*
Y-20074D01*
Y-20020D01*
Y-19966D01*
Y-19911D01*
Y-19858D01*
Y-19803D01*
Y-19749D01*
Y-19695D01*
Y-19641D01*
Y-19587D01*
Y-19533D01*
Y-19479D01*
Y-19425D01*
Y-19371D01*
Y-19317D01*
Y-19263D01*
Y-19209D01*
Y-19155D01*
Y-19101D01*
Y-19047D01*
Y-18993D01*
Y-18938D01*
Y-18884D01*
Y-18830D01*
Y-18776D01*
Y-18722D01*
Y-18668D01*
Y-18614D01*
Y-18560D01*
Y-18506D01*
Y-18452D01*
Y-18398D01*
Y-18344D01*
Y-18290D01*
Y-18236D01*
Y-18181D01*
Y-18127D01*
Y-18073D01*
Y-18019D01*
Y-17965D01*
Y-17911D01*
Y-17857D01*
Y-17803D01*
Y-17749D01*
Y-17695D01*
Y-17641D01*
Y-17587D01*
Y-17533D01*
Y-17479D01*
Y-17425D01*
Y-17371D01*
Y-17317D01*
Y-17263D01*
Y-17208D01*
Y-17154D01*
Y-17100D01*
Y-17046D01*
Y-16992D01*
Y-16938D01*
Y-16884D01*
Y-16830D01*
Y-16776D01*
Y-16722D01*
Y-16668D01*
Y-16614D01*
Y-16560D01*
Y-16506D01*
Y-16452D01*
Y-16398D01*
Y-16343D01*
Y-16289D01*
Y-16235D01*
Y-16181D01*
Y-16127D01*
Y-16073D01*
Y-16019D01*
Y-15965D01*
Y-15911D01*
Y-15857D01*
Y-15803D01*
Y-15749D01*
Y-15695D01*
Y-15641D01*
Y-15587D01*
Y-15532D01*
Y-15478D01*
Y-15424D01*
Y-15370D01*
Y-15316D01*
Y-15262D01*
Y-15208D01*
Y-15154D01*
Y-15100D01*
Y-15046D01*
Y-14992D01*
Y-14938D01*
Y-14884D01*
Y-14852D01*
D02*
G37*
G36*
X374986Y-34044D02*
X368900D01*
X368900Y-34045D01*
X368853Y-34068D01*
X368803Y-34084D01*
X368752Y-34095D01*
X368699Y-34098D01*
X368668D01*
Y-34130D01*
Y-34184D01*
Y-34238D01*
Y-34292D01*
Y-34346D01*
Y-34400D01*
Y-34454D01*
Y-34508D01*
Y-34562D01*
Y-34616D01*
Y-34670D01*
Y-34725D01*
Y-34779D01*
Y-34833D01*
Y-34887D01*
Y-34941D01*
Y-34995D01*
Y-35049D01*
Y-35103D01*
Y-35157D01*
Y-35211D01*
Y-35265D01*
Y-35319D01*
Y-35373D01*
Y-35427D01*
Y-35481D01*
Y-35535D01*
Y-35590D01*
Y-35644D01*
Y-35698D01*
Y-35752D01*
Y-35806D01*
Y-35860D01*
Y-35914D01*
Y-35968D01*
Y-36022D01*
Y-36076D01*
Y-36118D01*
X368701Y-36111D01*
X368753Y-36108D01*
X368807D01*
X368860Y-36111D01*
X368911Y-36121D01*
X368961Y-36138D01*
X369008Y-36161D01*
X369008Y-36162D01*
X374159D01*
X374212Y-36165D01*
X374263Y-36175D01*
X374313Y-36192D01*
X374360Y-36215D01*
X374404Y-36245D01*
X374443Y-36279D01*
X374468Y-36308D01*
X374497Y-36333D01*
X374522Y-36362D01*
X374551Y-36387D01*
X374586Y-36427D01*
X374615Y-36470D01*
X374638Y-36517D01*
X374655Y-36567D01*
X374665Y-36618D01*
X374668Y-36671D01*
Y-36725D01*
Y-36779D01*
Y-36833D01*
Y-36887D01*
Y-36941D01*
Y-36995D01*
Y-37049D01*
Y-37103D01*
Y-37157D01*
Y-37211D01*
Y-37265D01*
Y-37319D01*
Y-37374D01*
Y-37428D01*
Y-37482D01*
Y-37536D01*
Y-37590D01*
Y-37644D01*
Y-37698D01*
Y-37752D01*
Y-37806D01*
Y-37860D01*
Y-37914D01*
Y-37968D01*
Y-38022D01*
Y-38076D01*
Y-38130D01*
Y-38184D01*
Y-38238D01*
Y-38293D01*
Y-38347D01*
Y-38401D01*
Y-38455D01*
Y-38509D01*
Y-38563D01*
Y-38617D01*
Y-38671D01*
Y-38725D01*
Y-38779D01*
Y-38833D01*
Y-38887D01*
Y-38941D01*
Y-38995D01*
Y-39050D01*
Y-39103D01*
Y-39158D01*
Y-39212D01*
Y-39266D01*
Y-39320D01*
Y-39374D01*
Y-39428D01*
Y-39482D01*
Y-39536D01*
Y-39590D01*
Y-39644D01*
Y-39698D01*
Y-39752D01*
Y-39806D01*
Y-39860D01*
Y-39915D01*
Y-39968D01*
Y-40023D01*
Y-40077D01*
Y-40131D01*
Y-40185D01*
Y-40239D01*
Y-40293D01*
Y-40347D01*
Y-40401D01*
Y-40455D01*
Y-40509D01*
Y-40563D01*
Y-40617D01*
Y-40671D01*
Y-40725D01*
Y-40780D01*
Y-40834D01*
Y-40888D01*
Y-40942D01*
Y-40996D01*
Y-41050D01*
Y-41104D01*
Y-41158D01*
Y-41212D01*
Y-41266D01*
Y-41320D01*
Y-41374D01*
Y-41428D01*
Y-41482D01*
Y-41536D01*
Y-41590D01*
Y-41644D01*
Y-41699D01*
Y-41753D01*
Y-41807D01*
Y-41861D01*
Y-41915D01*
Y-41969D01*
Y-42023D01*
Y-42077D01*
Y-42131D01*
Y-42185D01*
Y-42239D01*
Y-42293D01*
Y-42347D01*
Y-42401D01*
X374665Y-42454D01*
X374655Y-42505D01*
X374638Y-42555D01*
X374615Y-42602D01*
X374594Y-42633D01*
X374584Y-42663D01*
X374561Y-42710D01*
X374532Y-42753D01*
X374497Y-42793D01*
X374458Y-42827D01*
X374414Y-42857D01*
X374367Y-42880D01*
X374337Y-42890D01*
X374306Y-42911D01*
X374259Y-42934D01*
X374209Y-42951D01*
X374158Y-42961D01*
X374105Y-42964D01*
X368684D01*
X368683Y-42965D01*
X368668Y-42972D01*
Y-42996D01*
Y-43050D01*
Y-43104D01*
Y-43158D01*
Y-43212D01*
Y-43266D01*
Y-43320D01*
Y-43374D01*
Y-43429D01*
Y-43483D01*
Y-43537D01*
Y-43591D01*
Y-43645D01*
Y-43699D01*
Y-43753D01*
Y-43807D01*
Y-43861D01*
Y-43915D01*
Y-43969D01*
Y-44023D01*
Y-44077D01*
Y-44131D01*
Y-44185D01*
Y-44239D01*
Y-44293D01*
Y-44348D01*
Y-44402D01*
Y-44456D01*
Y-44510D01*
Y-44564D01*
Y-44618D01*
Y-44672D01*
Y-44726D01*
Y-44780D01*
Y-44834D01*
Y-44888D01*
Y-44942D01*
Y-44996D01*
Y-45028D01*
X375094D01*
X375094Y-45028D01*
X375141Y-45004D01*
X375191Y-44987D01*
X375242Y-44977D01*
X375252Y-44977D01*
X375256Y-44973D01*
X375304Y-44950D01*
X375323Y-44944D01*
X375336Y-44929D01*
X375364Y-44904D01*
X375390Y-44875D01*
X375418Y-44850D01*
X375444Y-44821D01*
X375473Y-44796D01*
X375498Y-44767D01*
X375527Y-44742D01*
X375552Y-44713D01*
X375581Y-44688D01*
X375606Y-44659D01*
X375623Y-44644D01*
X375635Y-44634D01*
X375660Y-44605D01*
X375689Y-44579D01*
X375714Y-44551D01*
X375743Y-44525D01*
X375768Y-44497D01*
X375797Y-44471D01*
X375822Y-44442D01*
X375851Y-44417D01*
X375876Y-44388D01*
X375905Y-44363D01*
X375930Y-44334D01*
X375959Y-44309D01*
X375984Y-44280D01*
X376013Y-44255D01*
X376039Y-44226D01*
X376067Y-44201D01*
X376093Y-44172D01*
X376121Y-44147D01*
X376147Y-44118D01*
X376175Y-44093D01*
X376201Y-44064D01*
X376229Y-44039D01*
X376255Y-44010D01*
X376284Y-43985D01*
X376309Y-43956D01*
X376338Y-43931D01*
X376363Y-43902D01*
X376392Y-43877D01*
X376417Y-43848D01*
X376446Y-43823D01*
X376471Y-43794D01*
X376500Y-43769D01*
X376525Y-43740D01*
X376554Y-43714D01*
X376579Y-43686D01*
X376608Y-43660D01*
X376633Y-43632D01*
X376662Y-43606D01*
X376687Y-43578D01*
X376716Y-43552D01*
X376741Y-43523D01*
X376756Y-43511D01*
X376763Y-43491D01*
X376786Y-43444D01*
X376789Y-43440D01*
X376789Y-43430D01*
X376800Y-43379D01*
X376817Y-43329D01*
X376840Y-43282D01*
X376840Y-43282D01*
Y-43266D01*
Y-43212D01*
Y-43158D01*
Y-43104D01*
Y-43050D01*
Y-42996D01*
Y-42942D01*
Y-42888D01*
Y-42834D01*
Y-42780D01*
Y-42726D01*
Y-42672D01*
Y-42618D01*
Y-42564D01*
Y-42509D01*
Y-42455D01*
Y-42401D01*
Y-42347D01*
Y-42293D01*
Y-42239D01*
Y-42185D01*
Y-42131D01*
Y-42077D01*
Y-42023D01*
Y-41969D01*
Y-41915D01*
Y-41861D01*
Y-41807D01*
Y-41753D01*
Y-41699D01*
Y-41644D01*
Y-41590D01*
Y-41536D01*
Y-41482D01*
Y-41428D01*
Y-41374D01*
Y-41320D01*
Y-41266D01*
Y-41212D01*
Y-41158D01*
Y-41104D01*
Y-41050D01*
Y-40996D01*
Y-40942D01*
Y-40888D01*
Y-40834D01*
Y-40780D01*
Y-40725D01*
Y-40671D01*
Y-40617D01*
Y-40563D01*
Y-40509D01*
Y-40455D01*
Y-40401D01*
Y-40347D01*
Y-40293D01*
Y-40239D01*
Y-40185D01*
Y-40131D01*
Y-40077D01*
Y-40023D01*
Y-39968D01*
Y-39915D01*
Y-39860D01*
Y-39806D01*
Y-39752D01*
Y-39698D01*
Y-39644D01*
Y-39590D01*
Y-39536D01*
Y-39482D01*
Y-39428D01*
Y-39374D01*
Y-39320D01*
Y-39266D01*
Y-39212D01*
Y-39158D01*
Y-39103D01*
Y-39050D01*
Y-38995D01*
Y-38941D01*
Y-38887D01*
Y-38833D01*
Y-38779D01*
Y-38725D01*
Y-38671D01*
Y-38617D01*
Y-38563D01*
Y-38509D01*
Y-38455D01*
Y-38401D01*
Y-38347D01*
Y-38293D01*
Y-38238D01*
Y-38184D01*
Y-38130D01*
Y-38076D01*
Y-38022D01*
Y-37968D01*
Y-37914D01*
Y-37860D01*
Y-37806D01*
Y-37752D01*
Y-37698D01*
Y-37644D01*
Y-37590D01*
Y-37536D01*
Y-37482D01*
Y-37428D01*
Y-37374D01*
Y-37319D01*
Y-37265D01*
Y-37211D01*
Y-37157D01*
Y-37103D01*
Y-37049D01*
Y-36995D01*
Y-36941D01*
Y-36887D01*
Y-36833D01*
Y-36779D01*
Y-36725D01*
Y-36671D01*
Y-36617D01*
Y-36563D01*
Y-36509D01*
Y-36454D01*
Y-36400D01*
Y-36346D01*
Y-36292D01*
Y-36238D01*
Y-36184D01*
Y-36130D01*
Y-36076D01*
Y-36022D01*
Y-35968D01*
Y-35914D01*
Y-35860D01*
Y-35844D01*
X376840Y-35844D01*
X376817Y-35797D01*
X376800Y-35747D01*
X376789Y-35696D01*
X376786Y-35644D01*
Y-35628D01*
X376786Y-35628D01*
X376763Y-35581D01*
X376756Y-35561D01*
X376741Y-35549D01*
X376716Y-35520D01*
X376712Y-35516D01*
X376687Y-35495D01*
X376662Y-35466D01*
X376633Y-35440D01*
X376608Y-35412D01*
X376604Y-35408D01*
X376579Y-35386D01*
X376554Y-35358D01*
X376525Y-35332D01*
X376500Y-35304D01*
X376471Y-35278D01*
X376446Y-35249D01*
X376417Y-35224D01*
X376392Y-35195D01*
X376363Y-35170D01*
X376338Y-35141D01*
X376337Y-35141D01*
X376309Y-35116D01*
X376284Y-35087D01*
X376255Y-35062D01*
X376229Y-35033D01*
X376201Y-35008D01*
X376175Y-34979D01*
X376172Y-34976D01*
X376147Y-34954D01*
X376123Y-34928D01*
X376121Y-34925D01*
X376093Y-34900D01*
X376067Y-34871D01*
X376060Y-34864D01*
X376039Y-34846D01*
X376013Y-34817D01*
X375984Y-34792D01*
X375959Y-34763D01*
X375930Y-34738D01*
X375905Y-34709D01*
X375876Y-34684D01*
X375851Y-34655D01*
X375822Y-34629D01*
X375797Y-34601D01*
X375797Y-34601D01*
X375768Y-34576D01*
X375743Y-34547D01*
X375714Y-34521D01*
X375689Y-34493D01*
X375660Y-34467D01*
X375635Y-34438D01*
X375631Y-34435D01*
X375606Y-34413D01*
X375581Y-34385D01*
X375552Y-34359D01*
X375527Y-34330D01*
X375526Y-34330D01*
X375498Y-34305D01*
X375473Y-34276D01*
X375444Y-34251D01*
X375418Y-34222D01*
X375390Y-34197D01*
X375377Y-34182D01*
X375358Y-34176D01*
X375311Y-34153D01*
X375306Y-34149D01*
X375296Y-34149D01*
X375245Y-34139D01*
X375195Y-34122D01*
X375148Y-34099D01*
X375144Y-34095D01*
X375134Y-34095D01*
X375083Y-34084D01*
X375033Y-34068D01*
X374986Y-34045D01*
X374986Y-34044D01*
D02*
G37*
G36*
X359614D02*
X359277D01*
X359277Y-34045D01*
X359229Y-34068D01*
X359180Y-34084D01*
X359128Y-34095D01*
X359076Y-34098D01*
X359061D01*
X359060Y-34099D01*
X359013Y-34122D01*
X358983Y-34132D01*
X358975Y-34137D01*
X358952Y-34153D01*
X358905Y-34176D01*
X358886Y-34182D01*
X358873Y-34197D01*
X358844Y-34222D01*
X358819Y-34251D01*
X358790Y-34276D01*
X358765Y-34305D01*
X358736Y-34330D01*
X358711Y-34359D01*
X358682Y-34385D01*
X358657Y-34413D01*
X358628Y-34438D01*
X358603Y-34467D01*
X358574Y-34493D01*
X358549Y-34521D01*
X358520Y-34547D01*
X358495Y-34576D01*
X358466Y-34601D01*
X358440Y-34629D01*
X358412Y-34655D01*
X358386Y-34684D01*
X358362Y-34705D01*
X358358Y-34709D01*
X358332Y-34738D01*
X358304Y-34763D01*
X358278Y-34792D01*
X358249Y-34817D01*
X358224Y-34846D01*
X358195Y-34871D01*
X358187Y-34880D01*
X358170Y-34900D01*
X358141Y-34925D01*
X358139Y-34928D01*
X358116Y-34954D01*
X358099Y-34969D01*
X358087Y-34979D01*
X358062Y-35008D01*
X358033Y-35033D01*
X358008Y-35062D01*
X357979Y-35087D01*
X357954Y-35116D01*
X357925Y-35141D01*
X357900Y-35170D01*
X357871Y-35195D01*
X357846Y-35224D01*
X357817Y-35250D01*
X357792Y-35278D01*
X357763Y-35304D01*
X357742Y-35327D01*
X357738Y-35332D01*
X357709Y-35358D01*
X357684Y-35386D01*
X357655Y-35412D01*
X357630Y-35440D01*
X357601Y-35466D01*
X357575Y-35495D01*
X357547Y-35520D01*
X357525Y-35544D01*
X357525Y-35544D01*
X357517Y-35585D01*
X357500Y-35635D01*
X357477Y-35682D01*
X357477Y-35682D01*
Y-35698D01*
X357473Y-35750D01*
X357463Y-35801D01*
X357446Y-35851D01*
X357423Y-35898D01*
X357423Y-35899D01*
Y-35914D01*
Y-35968D01*
Y-36022D01*
Y-36076D01*
Y-36130D01*
Y-36184D01*
Y-36238D01*
Y-36292D01*
Y-36346D01*
Y-36400D01*
Y-36454D01*
Y-36509D01*
Y-36563D01*
Y-36617D01*
Y-36671D01*
Y-36725D01*
Y-36779D01*
Y-36833D01*
Y-36887D01*
Y-36941D01*
Y-36995D01*
Y-37049D01*
Y-37103D01*
Y-37157D01*
Y-37211D01*
Y-37265D01*
Y-37319D01*
Y-37374D01*
Y-37428D01*
Y-37482D01*
Y-37536D01*
Y-37590D01*
Y-37644D01*
Y-37698D01*
Y-37752D01*
Y-37806D01*
Y-37860D01*
Y-37914D01*
Y-37968D01*
Y-38022D01*
Y-38076D01*
Y-38130D01*
Y-38184D01*
Y-38238D01*
Y-38293D01*
Y-38347D01*
Y-38401D01*
Y-38455D01*
Y-38509D01*
Y-38563D01*
Y-38617D01*
Y-38671D01*
Y-38725D01*
Y-38779D01*
Y-38833D01*
Y-38887D01*
Y-38941D01*
Y-38995D01*
Y-39050D01*
Y-39103D01*
Y-39158D01*
Y-39212D01*
Y-39266D01*
Y-39320D01*
Y-39374D01*
Y-39428D01*
Y-39482D01*
Y-39536D01*
Y-39590D01*
Y-39644D01*
Y-39698D01*
Y-39752D01*
Y-39806D01*
Y-39860D01*
Y-39915D01*
Y-39968D01*
Y-40023D01*
Y-40077D01*
Y-40131D01*
Y-40185D01*
Y-40239D01*
Y-40293D01*
Y-40347D01*
Y-40401D01*
Y-40455D01*
Y-40509D01*
Y-40563D01*
Y-40617D01*
Y-40671D01*
Y-40725D01*
Y-40780D01*
Y-40834D01*
Y-40888D01*
Y-40942D01*
Y-40996D01*
Y-41050D01*
Y-41104D01*
Y-41158D01*
Y-41212D01*
Y-41266D01*
Y-41320D01*
Y-41374D01*
Y-41428D01*
Y-41482D01*
Y-41536D01*
Y-41590D01*
Y-41644D01*
Y-41699D01*
Y-41753D01*
Y-41807D01*
Y-41861D01*
Y-41915D01*
Y-41969D01*
Y-42023D01*
Y-42077D01*
Y-42131D01*
Y-42185D01*
Y-42239D01*
Y-42293D01*
Y-42347D01*
Y-42401D01*
Y-42455D01*
Y-42509D01*
Y-42564D01*
Y-42618D01*
Y-42672D01*
Y-42726D01*
Y-42780D01*
Y-42834D01*
Y-42888D01*
Y-42942D01*
Y-42996D01*
Y-43050D01*
Y-43104D01*
Y-43158D01*
Y-43212D01*
Y-43266D01*
Y-43320D01*
Y-43374D01*
Y-43429D01*
Y-43483D01*
Y-43537D01*
Y-43591D01*
Y-43645D01*
Y-43699D01*
Y-43753D01*
Y-43807D01*
Y-43861D01*
Y-43915D01*
Y-43969D01*
Y-44023D01*
Y-44077D01*
Y-44131D01*
Y-44185D01*
Y-44239D01*
Y-44293D01*
Y-44348D01*
Y-44402D01*
Y-44456D01*
Y-44510D01*
Y-44564D01*
Y-44618D01*
Y-44672D01*
Y-44726D01*
Y-44780D01*
Y-44834D01*
Y-44888D01*
Y-44942D01*
Y-44996D01*
Y-45012D01*
X357423Y-45012D01*
X357428Y-45022D01*
X357438Y-45028D01*
X357439Y-45028D01*
X359578D01*
X359578Y-45028D01*
X359594Y-45020D01*
Y-44996D01*
Y-44942D01*
Y-44888D01*
Y-44834D01*
Y-44780D01*
Y-44726D01*
Y-44672D01*
Y-44618D01*
Y-44564D01*
Y-44510D01*
Y-44456D01*
Y-44402D01*
Y-44348D01*
Y-44293D01*
Y-44239D01*
Y-44185D01*
Y-44131D01*
Y-44077D01*
Y-44023D01*
Y-43969D01*
Y-43915D01*
Y-43861D01*
Y-43807D01*
Y-43753D01*
Y-43699D01*
Y-43645D01*
Y-43591D01*
Y-43537D01*
Y-43483D01*
Y-43429D01*
Y-43374D01*
Y-43320D01*
Y-43266D01*
Y-43212D01*
Y-43158D01*
Y-43104D01*
Y-43050D01*
Y-42996D01*
Y-42942D01*
Y-42888D01*
Y-42834D01*
Y-42780D01*
Y-42726D01*
Y-42672D01*
Y-42618D01*
Y-42564D01*
Y-42509D01*
Y-42455D01*
Y-42401D01*
Y-42347D01*
Y-42293D01*
Y-42239D01*
Y-42185D01*
Y-42131D01*
Y-42077D01*
Y-42023D01*
Y-41969D01*
X359598Y-41916D01*
X359608Y-41865D01*
X359625Y-41815D01*
X359648Y-41768D01*
X359669Y-41738D01*
X359679Y-41707D01*
X359702Y-41660D01*
X359731Y-41617D01*
X359766Y-41577D01*
X359805Y-41543D01*
X359849Y-41513D01*
X359896Y-41490D01*
X359926Y-41480D01*
X359957Y-41460D01*
X360004Y-41436D01*
X360054Y-41419D01*
X360105Y-41409D01*
X360157Y-41406D01*
X363779D01*
X363832Y-41409D01*
X363883Y-41419D01*
X363933Y-41436D01*
X363980Y-41460D01*
X364011Y-41480D01*
X364022Y-41484D01*
X364041Y-41490D01*
X364088Y-41513D01*
X364132Y-41543D01*
X364171Y-41577D01*
X364206Y-41617D01*
X364235Y-41660D01*
X364258Y-41707D01*
X364268Y-41738D01*
X364289Y-41768D01*
X364312Y-41815D01*
X364329Y-41865D01*
X364339Y-41916D01*
X364343Y-41969D01*
Y-42023D01*
Y-42077D01*
Y-42131D01*
Y-42185D01*
Y-42239D01*
Y-42293D01*
Y-42347D01*
Y-42401D01*
Y-42455D01*
Y-42509D01*
Y-42564D01*
Y-42618D01*
Y-42672D01*
Y-42726D01*
Y-42780D01*
Y-42834D01*
Y-42888D01*
Y-42942D01*
Y-42996D01*
Y-43050D01*
Y-43104D01*
Y-43158D01*
Y-43212D01*
Y-43266D01*
Y-43320D01*
Y-43374D01*
Y-43429D01*
Y-43483D01*
Y-43537D01*
Y-43591D01*
Y-43645D01*
Y-43699D01*
Y-43753D01*
Y-43807D01*
Y-43861D01*
Y-43915D01*
Y-43969D01*
Y-44023D01*
Y-44077D01*
Y-44131D01*
Y-44185D01*
Y-44239D01*
Y-44293D01*
Y-44348D01*
Y-44402D01*
Y-44456D01*
Y-44510D01*
Y-44564D01*
Y-44618D01*
Y-44672D01*
Y-44726D01*
Y-44780D01*
Y-44834D01*
Y-44888D01*
Y-44942D01*
Y-44996D01*
Y-45012D01*
X364343Y-45012D01*
X364348Y-45022D01*
X364358Y-45028D01*
X364359Y-45028D01*
X366498D01*
X366498Y-45028D01*
X366514Y-45020D01*
Y-44996D01*
Y-44942D01*
Y-44888D01*
Y-44834D01*
Y-44780D01*
Y-44726D01*
Y-44672D01*
Y-44618D01*
Y-44564D01*
Y-44510D01*
Y-44456D01*
Y-44402D01*
Y-44348D01*
Y-44293D01*
Y-44239D01*
Y-44185D01*
Y-44131D01*
Y-44077D01*
Y-44023D01*
Y-43969D01*
Y-43915D01*
Y-43861D01*
Y-43807D01*
Y-43753D01*
Y-43699D01*
Y-43645D01*
Y-43591D01*
Y-43537D01*
Y-43483D01*
Y-43429D01*
Y-43374D01*
Y-43320D01*
Y-43266D01*
Y-43212D01*
Y-43158D01*
Y-43104D01*
Y-43050D01*
Y-42996D01*
Y-42942D01*
Y-42888D01*
Y-42834D01*
Y-42780D01*
Y-42726D01*
Y-42672D01*
Y-42618D01*
Y-42564D01*
Y-42509D01*
Y-42455D01*
Y-42401D01*
Y-42347D01*
Y-42293D01*
Y-42239D01*
Y-42185D01*
Y-42131D01*
Y-42077D01*
Y-42023D01*
Y-41969D01*
Y-41915D01*
Y-41861D01*
Y-41807D01*
Y-41753D01*
Y-41699D01*
Y-41644D01*
Y-41590D01*
Y-41536D01*
Y-41482D01*
Y-41428D01*
Y-41374D01*
Y-41320D01*
Y-41266D01*
Y-41212D01*
Y-41160D01*
X366498Y-41142D01*
X366470Y-41117D01*
X366466Y-41113D01*
X366444Y-41088D01*
X366415Y-41063D01*
X366390Y-41034D01*
X366383Y-41027D01*
X366361Y-41009D01*
X366349Y-40994D01*
X366329Y-40988D01*
X366282Y-40964D01*
X366239Y-40935D01*
X366199Y-40901D01*
X366174Y-40872D01*
X366145Y-40847D01*
X366120Y-40818D01*
X366091Y-40793D01*
X366066Y-40764D01*
X366037Y-40738D01*
X366012Y-40710D01*
X365983Y-40685D01*
X365958Y-40656D01*
X365929Y-40630D01*
X365904Y-40602D01*
X365904Y-40602D01*
X365875Y-40576D01*
X365849Y-40548D01*
X365821Y-40522D01*
X365817Y-40518D01*
X365795Y-40494D01*
X365767Y-40468D01*
X365741Y-40439D01*
X365713Y-40414D01*
X365687Y-40385D01*
X365659Y-40360D01*
X365633Y-40331D01*
X365604Y-40306D01*
X365579Y-40277D01*
X365550Y-40252D01*
X365525Y-40223D01*
X365496Y-40198D01*
X365471Y-40169D01*
X365442Y-40144D01*
X365417Y-40115D01*
X365388Y-40090D01*
X365363Y-40061D01*
X365334Y-40036D01*
X365309Y-40007D01*
X365280Y-39982D01*
X365255Y-39953D01*
X365226Y-39928D01*
X365201Y-39899D01*
X365172Y-39874D01*
X365147Y-39845D01*
X365118Y-39819D01*
X365093Y-39791D01*
X365085Y-39784D01*
X365064Y-39765D01*
X365039Y-39737D01*
X365010Y-39711D01*
X364984Y-39683D01*
X364956Y-39657D01*
X364931Y-39628D01*
X364902Y-39603D01*
X364876Y-39574D01*
X364848Y-39549D01*
X364822Y-39520D01*
X364794Y-39495D01*
X364768Y-39466D01*
X364739Y-39441D01*
X364714Y-39412D01*
X364685Y-39387D01*
X364660Y-39358D01*
X364631Y-39333D01*
X364606Y-39304D01*
X364577Y-39279D01*
X364552Y-39250D01*
X364523Y-39225D01*
X364498Y-39196D01*
X364469Y-39171D01*
X364444Y-39142D01*
X364415Y-39117D01*
X364390Y-39088D01*
X364361Y-39063D01*
X364343Y-39042D01*
Y-39050D01*
Y-39103D01*
Y-39158D01*
Y-39212D01*
Y-39266D01*
X364339Y-39318D01*
X364329Y-39369D01*
X364312Y-39419D01*
X364289Y-39466D01*
X364260Y-39510D01*
X364225Y-39549D01*
X364186Y-39584D01*
X364142Y-39613D01*
X364095Y-39636D01*
X364046Y-39653D01*
X363994Y-39663D01*
X363942Y-39667D01*
X359995D01*
X359943Y-39663D01*
X359891Y-39653D01*
X359842Y-39636D01*
X359795Y-39613D01*
X359751Y-39584D01*
X359712Y-39549D01*
X359677Y-39510D01*
X359648Y-39466D01*
X359625Y-39419D01*
X359608Y-39369D01*
X359598Y-39318D01*
X359594Y-39266D01*
Y-39212D01*
Y-39158D01*
Y-39103D01*
Y-39050D01*
Y-38995D01*
Y-38941D01*
Y-38887D01*
Y-38833D01*
Y-38779D01*
Y-38725D01*
Y-38671D01*
Y-38617D01*
Y-38563D01*
Y-38509D01*
Y-38455D01*
Y-38401D01*
Y-38347D01*
Y-38293D01*
Y-38238D01*
Y-38184D01*
Y-38130D01*
Y-38076D01*
Y-38022D01*
Y-37968D01*
Y-37914D01*
Y-37860D01*
Y-37806D01*
Y-37752D01*
Y-37698D01*
Y-37644D01*
Y-37590D01*
Y-37536D01*
Y-37482D01*
Y-37428D01*
Y-37374D01*
Y-37319D01*
Y-37265D01*
Y-37211D01*
Y-37157D01*
Y-37103D01*
Y-37049D01*
Y-36995D01*
Y-36941D01*
Y-36887D01*
Y-36833D01*
Y-36779D01*
Y-36725D01*
Y-36671D01*
Y-36617D01*
Y-36563D01*
Y-36509D01*
Y-36454D01*
Y-36400D01*
Y-36346D01*
Y-36292D01*
X359598Y-36240D01*
X359608Y-36189D01*
X359625Y-36139D01*
X359648Y-36092D01*
X359677Y-36048D01*
X359712Y-36009D01*
X359751Y-35974D01*
X359795Y-35945D01*
X359842Y-35922D01*
X359891Y-35905D01*
X359943Y-35895D01*
X359995Y-35891D01*
X361463D01*
X361442Y-35873D01*
X361417Y-35844D01*
X361388Y-35819D01*
X361362Y-35790D01*
X361334Y-35765D01*
X361308Y-35736D01*
X361280Y-35711D01*
X361254Y-35682D01*
X361226Y-35657D01*
X361200Y-35628D01*
X361171Y-35603D01*
X361146Y-35574D01*
X361132Y-35561D01*
X361117Y-35549D01*
X361092Y-35520D01*
X361088Y-35516D01*
X361063Y-35495D01*
X361038Y-35466D01*
X361009Y-35440D01*
X360984Y-35412D01*
X360955Y-35386D01*
X360930Y-35358D01*
X360901Y-35332D01*
X360876Y-35304D01*
X360847Y-35278D01*
X360822Y-35249D01*
X360818Y-35246D01*
X360793Y-35224D01*
X360768Y-35195D01*
X360739Y-35170D01*
X360734Y-35164D01*
X360714Y-35141D01*
X360685Y-35116D01*
X360660Y-35087D01*
X360631Y-35062D01*
X360606Y-35033D01*
X360577Y-35008D01*
X360551Y-34979D01*
X360548Y-34976D01*
X360523Y-34954D01*
X360497Y-34925D01*
X360469Y-34900D01*
X360443Y-34871D01*
X360415Y-34846D01*
X360389Y-34817D01*
X360361Y-34792D01*
X360335Y-34763D01*
X360306Y-34738D01*
X360281Y-34709D01*
X360277Y-34705D01*
X360252Y-34684D01*
X360227Y-34655D01*
X360198Y-34629D01*
X360173Y-34601D01*
X360144Y-34576D01*
X360119Y-34547D01*
X360090Y-34521D01*
X360065Y-34493D01*
X360036Y-34467D01*
X360011Y-34438D01*
X359982Y-34413D01*
X359957Y-34385D01*
X359928Y-34359D01*
X359903Y-34330D01*
X359874Y-34305D01*
X359849Y-34276D01*
X359820Y-34251D01*
X359795Y-34222D01*
X359766Y-34197D01*
X359740Y-34168D01*
X359712Y-34143D01*
X359686Y-34114D01*
X359682Y-34111D01*
X359658Y-34089D01*
X359632Y-34060D01*
X359614Y-34044D01*
D02*
G37*
G36*
X355415D02*
X348357D01*
X348356Y-34045D01*
X348309Y-34068D01*
X348259Y-34084D01*
X348208Y-34095D01*
X348156Y-34098D01*
X348086D01*
X348086Y-34099D01*
X348039Y-34122D01*
X347989Y-34139D01*
X347938Y-34149D01*
X347928Y-34149D01*
X347923Y-34153D01*
X347877Y-34176D01*
X347857Y-34182D01*
X347844Y-34197D01*
X347816Y-34222D01*
X347790Y-34251D01*
X347762Y-34276D01*
X347736Y-34305D01*
X347708Y-34330D01*
X347686Y-34355D01*
X347682Y-34359D01*
X347653Y-34385D01*
X347628Y-34413D01*
X347599Y-34438D01*
X347574Y-34467D01*
X347545Y-34493D01*
X347520Y-34521D01*
X347491Y-34547D01*
X347466Y-34576D01*
X347437Y-34601D01*
X347412Y-34629D01*
X347383Y-34655D01*
X347358Y-34684D01*
X347333Y-34705D01*
X347329Y-34709D01*
X347315Y-34725D01*
X347304Y-34738D01*
X347275Y-34763D01*
X347250Y-34792D01*
X347221Y-34817D01*
X347196Y-34846D01*
X347167Y-34871D01*
X347159Y-34880D01*
X347142Y-34900D01*
X347113Y-34925D01*
X347105Y-34934D01*
X347088Y-34954D01*
X347059Y-34979D01*
X347033Y-35008D01*
X347005Y-35033D01*
X346979Y-35062D01*
X346951Y-35087D01*
X346925Y-35116D01*
X346897Y-35141D01*
X346871Y-35170D01*
X346842Y-35195D01*
X346817Y-35224D01*
X346788Y-35249D01*
X346763Y-35278D01*
X346734Y-35304D01*
X346709Y-35332D01*
X346680Y-35358D01*
X346655Y-35386D01*
X346626Y-35412D01*
X346611Y-35429D01*
X346601Y-35440D01*
X346572Y-35466D01*
X346566Y-35473D01*
X346547Y-35495D01*
X346522Y-35516D01*
X346518Y-35520D01*
X346493Y-35549D01*
X346478Y-35561D01*
X346472Y-35581D01*
X346448Y-35628D01*
X346445Y-35633D01*
X346445Y-35642D01*
X346434Y-35693D01*
X346417Y-35743D01*
X346394Y-35790D01*
X346394Y-35791D01*
Y-35806D01*
Y-35860D01*
Y-35914D01*
Y-35968D01*
Y-36022D01*
Y-36076D01*
Y-36130D01*
Y-36184D01*
Y-36238D01*
Y-36292D01*
Y-36346D01*
Y-36400D01*
Y-36454D01*
Y-36509D01*
Y-36563D01*
Y-36617D01*
Y-36671D01*
Y-36725D01*
Y-36779D01*
Y-36833D01*
Y-36887D01*
Y-36941D01*
Y-36995D01*
Y-37049D01*
Y-37103D01*
Y-37157D01*
Y-37211D01*
Y-37265D01*
Y-37319D01*
Y-37374D01*
Y-37428D01*
Y-37482D01*
Y-37536D01*
Y-37590D01*
Y-37644D01*
Y-37698D01*
Y-37752D01*
Y-37806D01*
Y-37860D01*
Y-37914D01*
Y-37968D01*
Y-38022D01*
Y-38076D01*
Y-38130D01*
Y-38184D01*
Y-38238D01*
Y-38293D01*
Y-38347D01*
Y-38401D01*
Y-38455D01*
Y-38509D01*
Y-38563D01*
Y-38617D01*
Y-38671D01*
Y-38725D01*
Y-38779D01*
Y-38833D01*
Y-38887D01*
Y-38941D01*
Y-38995D01*
Y-39050D01*
Y-39103D01*
Y-39158D01*
Y-39212D01*
Y-39266D01*
Y-39320D01*
Y-39374D01*
Y-39428D01*
Y-39482D01*
Y-39536D01*
Y-39590D01*
Y-39644D01*
Y-39659D01*
X346394Y-39660D01*
X346417Y-39707D01*
X346428Y-39737D01*
X346448Y-39768D01*
X346472Y-39815D01*
X346478Y-39834D01*
X346493Y-39847D01*
X346518Y-39876D01*
X346547Y-39901D01*
X346572Y-39930D01*
X346601Y-39955D01*
X346626Y-39984D01*
X346655Y-40009D01*
X346680Y-40038D01*
X346709Y-40064D01*
X346744Y-40103D01*
X346773Y-40146D01*
X346796Y-40194D01*
X346802Y-40213D01*
X346811Y-40220D01*
X346817Y-40226D01*
X346842Y-40255D01*
X346871Y-40280D01*
X346897Y-40309D01*
X346925Y-40334D01*
X346951Y-40363D01*
X346979Y-40388D01*
X347005Y-40417D01*
X347033Y-40442D01*
X347059Y-40471D01*
X347088Y-40496D01*
X347113Y-40525D01*
X347142Y-40550D01*
X347167Y-40579D01*
X347196Y-40604D01*
X347221Y-40633D01*
X347250Y-40658D01*
X347275Y-40687D01*
X347304Y-40712D01*
X347329Y-40741D01*
X347358Y-40766D01*
X347383Y-40795D01*
X347412Y-40820D01*
X347437Y-40849D01*
X347451Y-40861D01*
X347466Y-40874D01*
X347491Y-40903D01*
X347517Y-40926D01*
X347520Y-40929D01*
X347545Y-40957D01*
X347574Y-40983D01*
X347599Y-41011D01*
X347628Y-41037D01*
X347653Y-41065D01*
X347682Y-41091D01*
X347708Y-41120D01*
X347736Y-41145D01*
X347762Y-41174D01*
X347787Y-41196D01*
X347790Y-41199D01*
X347816Y-41228D01*
X347844Y-41253D01*
X347870Y-41282D01*
X347898Y-41307D01*
X347924Y-41336D01*
X347953Y-41361D01*
X347987Y-41400D01*
X348016Y-41444D01*
X348039Y-41491D01*
X348056Y-41541D01*
X348066Y-41592D01*
X348070Y-41644D01*
Y-41699D01*
Y-41753D01*
X348066Y-41805D01*
X348056Y-41856D01*
X348039Y-41906D01*
X348016Y-41953D01*
X347987Y-41997D01*
X347953Y-42036D01*
X347938Y-42049D01*
X347933Y-42062D01*
X347931Y-42068D01*
X347908Y-42115D01*
X347887Y-42146D01*
X347881Y-42166D01*
X347877Y-42176D01*
X347854Y-42223D01*
X347825Y-42267D01*
X347790Y-42306D01*
X347776Y-42319D01*
X347769Y-42338D01*
X347746Y-42386D01*
X347725Y-42416D01*
X347715Y-42447D01*
X347692Y-42494D01*
X347671Y-42524D01*
X347661Y-42555D01*
X347638Y-42602D01*
X347609Y-42645D01*
X347574Y-42685D01*
X347559Y-42698D01*
X347553Y-42717D01*
X347530Y-42764D01*
X347509Y-42795D01*
X347505Y-42807D01*
X347499Y-42825D01*
X347476Y-42872D01*
X347446Y-42916D01*
X347412Y-42955D01*
X347397Y-42968D01*
X347396Y-42970D01*
X347391Y-42987D01*
X347368Y-43034D01*
X347347Y-43065D01*
X347342Y-43078D01*
X347337Y-43095D01*
X347313Y-43142D01*
X347284Y-43186D01*
X347250Y-43225D01*
X347235Y-43238D01*
X347229Y-43257D01*
X347205Y-43305D01*
X347185Y-43335D01*
X347181Y-43347D01*
X347174Y-43366D01*
X347151Y-43413D01*
X347122Y-43456D01*
X347088Y-43496D01*
X347073Y-43509D01*
X347069Y-43521D01*
X347066Y-43528D01*
X347043Y-43575D01*
X347023Y-43606D01*
X347012Y-43636D01*
X346989Y-43683D01*
X346960Y-43727D01*
X346925Y-43766D01*
X346911Y-43779D01*
X346910Y-43781D01*
X346904Y-43798D01*
X346881Y-43845D01*
X346860Y-43876D01*
X346850Y-43906D01*
X346827Y-43953D01*
X346798Y-43997D01*
X346763Y-44036D01*
X346748Y-44049D01*
X346742Y-44069D01*
X346719Y-44115D01*
X346698Y-44146D01*
X346688Y-44177D01*
X346665Y-44224D01*
X346636Y-44267D01*
X346601Y-44307D01*
X346586Y-44319D01*
X346586Y-44322D01*
X346580Y-44339D01*
X346556Y-44386D01*
X346536Y-44417D01*
X346532Y-44429D01*
X346526Y-44447D01*
X346502Y-44494D01*
X346473Y-44537D01*
X346439Y-44577D01*
X346424Y-44590D01*
X346422Y-44595D01*
X346417Y-44609D01*
X346394Y-44656D01*
X346374Y-44687D01*
X346363Y-44717D01*
X346340Y-44764D01*
X346311Y-44808D01*
X346277Y-44847D01*
X346262Y-44860D01*
X346262Y-44861D01*
X346255Y-44879D01*
X346232Y-44926D01*
X346212Y-44957D01*
X346211Y-44958D01*
X346201Y-44987D01*
X346181Y-45028D01*
X348441D01*
X348442Y-45028D01*
X348489Y-45004D01*
X348508Y-44998D01*
X348521Y-44983D01*
X348550Y-44958D01*
X348575Y-44929D01*
X348590Y-44916D01*
D01*
X348596Y-44897D01*
X348619Y-44850D01*
X348640Y-44819D01*
X348650Y-44789D01*
X348674Y-44742D01*
X348703Y-44698D01*
X348737Y-44659D01*
X348752Y-44646D01*
X348758Y-44627D01*
X348782Y-44580D01*
X348792Y-44564D01*
X348802Y-44549D01*
X348812Y-44519D01*
X348836Y-44471D01*
X348856Y-44441D01*
X348867Y-44410D01*
X348890Y-44363D01*
X348919Y-44320D01*
X348953Y-44280D01*
X348968Y-44267D01*
X348975Y-44248D01*
X348998Y-44201D01*
X349018Y-44170D01*
X349029Y-44140D01*
X349052Y-44093D01*
X349081Y-44050D01*
X349116Y-44010D01*
X349130Y-43997D01*
X349137Y-43978D01*
X349160Y-43931D01*
X349181Y-43900D01*
X349191Y-43870D01*
X349214Y-43823D01*
X349243Y-43779D01*
X349278Y-43740D01*
X349292Y-43727D01*
X349299Y-43708D01*
X349322Y-43661D01*
X349343Y-43630D01*
X349353Y-43600D01*
X349376Y-43552D01*
X349405Y-43509D01*
X349440Y-43469D01*
X349455Y-43457D01*
X349461Y-43437D01*
X349484Y-43390D01*
X349505Y-43360D01*
X349515Y-43329D01*
X349538Y-43282D01*
X349559Y-43251D01*
X349569Y-43221D01*
X349592Y-43174D01*
X349622Y-43130D01*
X349656Y-43091D01*
X349671Y-43078D01*
X349677Y-43059D01*
X349701Y-43012D01*
X349721Y-42981D01*
X349723Y-42977D01*
X349731Y-42951D01*
X349755Y-42904D01*
X349784Y-42860D01*
X349818Y-42821D01*
X349833Y-42808D01*
X349840Y-42788D01*
X349863Y-42742D01*
X349883Y-42711D01*
X349894Y-42680D01*
X349917Y-42633D01*
X349946Y-42590D01*
X349981Y-42550D01*
X349995Y-42538D01*
X350002Y-42518D01*
X350025Y-42471D01*
X350046Y-42440D01*
X350056Y-42410D01*
X350079Y-42363D01*
X350100Y-42332D01*
X350101Y-42328D01*
X350110Y-42302D01*
X350133Y-42255D01*
X350162Y-42211D01*
X350197Y-42172D01*
X350207Y-42163D01*
X350212Y-42159D01*
X350218Y-42140D01*
X350241Y-42093D01*
X350262Y-42062D01*
X350272Y-42032D01*
X350295Y-41985D01*
X350324Y-41941D01*
X350359Y-41902D01*
X350374Y-41889D01*
X350380Y-41870D01*
X350403Y-41822D01*
X350424Y-41792D01*
X350427Y-41784D01*
X350434Y-41761D01*
X350458Y-41714D01*
X350487Y-41671D01*
X350521Y-41631D01*
X350561Y-41597D01*
X350604Y-41568D01*
X350651Y-41544D01*
X350701Y-41528D01*
X350752Y-41517D01*
X350805Y-41514D01*
X352859D01*
X352911Y-41517D01*
X352963Y-41528D01*
X353012Y-41544D01*
X353059Y-41568D01*
X353103Y-41597D01*
X353142Y-41631D01*
X353177Y-41671D01*
X353206Y-41714D01*
X353229Y-41761D01*
X353246Y-41811D01*
X353256Y-41862D01*
X353260Y-41915D01*
Y-41969D01*
Y-41984D01*
X353260Y-41985D01*
X353283Y-42032D01*
X353300Y-42081D01*
X353310Y-42133D01*
X353314Y-42185D01*
Y-42239D01*
X353310Y-42292D01*
X353300Y-42343D01*
X353283Y-42393D01*
X353260Y-42440D01*
X353260Y-42440D01*
Y-42455D01*
Y-42509D01*
Y-42564D01*
Y-42618D01*
Y-42672D01*
Y-42726D01*
Y-42780D01*
Y-42834D01*
Y-42888D01*
Y-42942D01*
Y-42996D01*
Y-43050D01*
Y-43104D01*
Y-43158D01*
Y-43212D01*
Y-43266D01*
Y-43320D01*
Y-43374D01*
Y-43429D01*
Y-43483D01*
Y-43537D01*
Y-43591D01*
Y-43645D01*
Y-43699D01*
Y-43753D01*
Y-43807D01*
Y-43861D01*
Y-43915D01*
Y-43969D01*
Y-44023D01*
Y-44077D01*
Y-44131D01*
Y-44185D01*
Y-44239D01*
Y-44293D01*
Y-44348D01*
Y-44402D01*
Y-44456D01*
Y-44510D01*
Y-44564D01*
Y-44618D01*
Y-44672D01*
Y-44726D01*
Y-44780D01*
Y-44834D01*
Y-44888D01*
Y-44942D01*
Y-44958D01*
X353260Y-44958D01*
X353283Y-45005D01*
X353289Y-45022D01*
X353291Y-45028D01*
X355433D01*
X355433Y-45028D01*
X355435Y-44998D01*
X355445Y-44947D01*
X355462Y-44897D01*
X355485Y-44850D01*
X355486Y-44849D01*
Y-44834D01*
Y-44780D01*
Y-44726D01*
Y-44672D01*
Y-44618D01*
Y-44564D01*
Y-44510D01*
Y-44456D01*
Y-44402D01*
Y-44348D01*
Y-44293D01*
Y-44239D01*
Y-44185D01*
Y-44131D01*
Y-44077D01*
Y-44023D01*
Y-43969D01*
Y-43915D01*
Y-43861D01*
Y-43807D01*
Y-43753D01*
Y-43699D01*
Y-43645D01*
Y-43591D01*
Y-43537D01*
Y-43483D01*
Y-43429D01*
Y-43374D01*
Y-43320D01*
Y-43266D01*
Y-43212D01*
Y-43158D01*
Y-43104D01*
Y-43050D01*
Y-42996D01*
Y-42942D01*
Y-42888D01*
Y-42834D01*
Y-42780D01*
Y-42726D01*
Y-42672D01*
Y-42618D01*
Y-42564D01*
Y-42509D01*
Y-42455D01*
Y-42401D01*
Y-42347D01*
Y-42293D01*
Y-42239D01*
Y-42185D01*
Y-42131D01*
Y-42077D01*
Y-42023D01*
Y-41969D01*
Y-41915D01*
Y-41861D01*
Y-41807D01*
Y-41753D01*
Y-41699D01*
Y-41644D01*
Y-41590D01*
Y-41536D01*
Y-41482D01*
Y-41428D01*
Y-41374D01*
Y-41320D01*
Y-41266D01*
Y-41212D01*
Y-41158D01*
Y-41104D01*
Y-41050D01*
Y-40996D01*
Y-40942D01*
Y-40888D01*
Y-40834D01*
Y-40780D01*
Y-40725D01*
Y-40671D01*
Y-40617D01*
Y-40563D01*
Y-40509D01*
Y-40455D01*
Y-40401D01*
Y-40347D01*
Y-40293D01*
Y-40239D01*
Y-40185D01*
Y-40131D01*
Y-40077D01*
Y-40023D01*
Y-39968D01*
Y-39915D01*
Y-39860D01*
Y-39806D01*
Y-39752D01*
Y-39698D01*
Y-39644D01*
Y-39590D01*
Y-39536D01*
Y-39482D01*
Y-39428D01*
Y-39374D01*
Y-39320D01*
Y-39266D01*
Y-39212D01*
Y-39158D01*
Y-39103D01*
Y-39050D01*
Y-38995D01*
Y-38941D01*
Y-38887D01*
Y-38833D01*
Y-38779D01*
Y-38725D01*
Y-38671D01*
Y-38617D01*
Y-38563D01*
Y-38509D01*
Y-38455D01*
Y-38401D01*
Y-38347D01*
Y-38293D01*
Y-38238D01*
Y-38184D01*
Y-38130D01*
Y-38076D01*
Y-38022D01*
Y-37968D01*
Y-37914D01*
Y-37860D01*
Y-37806D01*
Y-37752D01*
Y-37698D01*
Y-37644D01*
Y-37590D01*
Y-37536D01*
Y-37482D01*
Y-37428D01*
Y-37374D01*
Y-37319D01*
Y-37265D01*
Y-37211D01*
Y-37157D01*
Y-37103D01*
Y-37049D01*
Y-36995D01*
Y-36941D01*
Y-36887D01*
Y-36833D01*
Y-36779D01*
Y-36725D01*
Y-36671D01*
Y-36617D01*
Y-36563D01*
Y-36509D01*
Y-36454D01*
Y-36400D01*
Y-36346D01*
Y-36292D01*
Y-36238D01*
Y-36184D01*
Y-36130D01*
Y-36076D01*
Y-36022D01*
Y-35968D01*
Y-35914D01*
Y-35860D01*
Y-35806D01*
Y-35752D01*
Y-35698D01*
Y-35644D01*
Y-35590D01*
Y-35535D01*
Y-35481D01*
Y-35427D01*
Y-35373D01*
Y-35319D01*
Y-35265D01*
Y-35211D01*
Y-35157D01*
Y-35103D01*
Y-35049D01*
Y-34995D01*
Y-34941D01*
Y-34887D01*
Y-34833D01*
Y-34779D01*
Y-34725D01*
Y-34670D01*
Y-34616D01*
Y-34562D01*
Y-34508D01*
Y-34454D01*
Y-34400D01*
Y-34346D01*
Y-34292D01*
Y-34238D01*
Y-34184D01*
Y-34169D01*
X355485Y-34168D01*
X355462Y-34121D01*
X355445Y-34071D01*
X355443Y-34060D01*
X355443Y-34058D01*
X355416Y-34045D01*
X355415Y-34044D01*
D02*
G37*
G36*
X343900D02*
X336841D01*
X336841Y-34045D01*
X336794Y-34068D01*
X336744Y-34084D01*
X336693Y-34095D01*
X336640Y-34098D01*
X336571D01*
X336571Y-34099D01*
X336524Y-34122D01*
X336474Y-34139D01*
X336433Y-34147D01*
X336417Y-34161D01*
X336408Y-34168D01*
X336396Y-34182D01*
X336383Y-34197D01*
X336354Y-34222D01*
X336329Y-34251D01*
X336300Y-34276D01*
X336275Y-34305D01*
X336246Y-34330D01*
X336221Y-34359D01*
X336192Y-34385D01*
X336167Y-34413D01*
X336138Y-34438D01*
X336124Y-34454D01*
X336113Y-34467D01*
X336084Y-34492D01*
X336084Y-34493D01*
X336059Y-34521D01*
X336030Y-34547D01*
X336005Y-34576D01*
X335976Y-34601D01*
X335951Y-34629D01*
X335922Y-34655D01*
X335897Y-34684D01*
X335868Y-34709D01*
X335843Y-34738D01*
X335814Y-34763D01*
X335788Y-34792D01*
X335760Y-34817D01*
X335735Y-34846D01*
X335706Y-34871D01*
X335680Y-34900D01*
X335652Y-34925D01*
X335626Y-34954D01*
X335598Y-34979D01*
X335572Y-35008D01*
X335543Y-35033D01*
X335518Y-35062D01*
X335489Y-35087D01*
X335464Y-35116D01*
X335435Y-35141D01*
X335410Y-35170D01*
X335381Y-35195D01*
X335381Y-35196D01*
X335356Y-35224D01*
X335331Y-35246D01*
X335327Y-35249D01*
X335302Y-35278D01*
X335273Y-35304D01*
X335248Y-35332D01*
X335219Y-35358D01*
X335194Y-35386D01*
X335165Y-35412D01*
X335140Y-35440D01*
X335111Y-35466D01*
X335104Y-35473D01*
X335086Y-35495D01*
X335057Y-35520D01*
X335032Y-35549D01*
X335011Y-35567D01*
X335003Y-35574D01*
X334978Y-35603D01*
X334963Y-35616D01*
X334956Y-35635D01*
X334933Y-35682D01*
X334933Y-35682D01*
Y-35698D01*
X334929Y-35750D01*
X334919Y-35801D01*
X334902Y-35851D01*
X334879Y-35898D01*
X334879Y-35899D01*
Y-35914D01*
Y-35968D01*
Y-36022D01*
Y-36076D01*
Y-36130D01*
Y-36184D01*
Y-36238D01*
Y-36292D01*
Y-36346D01*
Y-36400D01*
Y-36454D01*
Y-36509D01*
Y-36563D01*
Y-36617D01*
Y-36671D01*
Y-36725D01*
Y-36779D01*
Y-36833D01*
Y-36887D01*
Y-36941D01*
Y-36995D01*
Y-37049D01*
Y-37103D01*
Y-37157D01*
Y-37211D01*
Y-37265D01*
Y-37319D01*
Y-37374D01*
Y-37428D01*
Y-37482D01*
Y-37536D01*
Y-37590D01*
Y-37644D01*
Y-37698D01*
Y-37752D01*
Y-37806D01*
Y-37860D01*
Y-37914D01*
Y-37968D01*
Y-38022D01*
Y-38076D01*
Y-38130D01*
Y-38184D01*
Y-38238D01*
Y-38293D01*
Y-38347D01*
Y-38401D01*
Y-38455D01*
Y-38509D01*
Y-38563D01*
Y-38617D01*
Y-38671D01*
Y-38725D01*
Y-38779D01*
Y-38833D01*
Y-38887D01*
Y-38941D01*
Y-38995D01*
Y-39050D01*
Y-39103D01*
Y-39158D01*
Y-39212D01*
Y-39266D01*
Y-39320D01*
Y-39374D01*
Y-39428D01*
Y-39482D01*
Y-39536D01*
Y-39590D01*
Y-39644D01*
Y-39698D01*
Y-39752D01*
Y-39806D01*
Y-39860D01*
Y-39915D01*
Y-39968D01*
Y-40023D01*
Y-40077D01*
Y-40131D01*
Y-40185D01*
Y-40239D01*
Y-40293D01*
Y-40347D01*
Y-40401D01*
Y-40455D01*
Y-40509D01*
Y-40563D01*
Y-40617D01*
Y-40671D01*
Y-40725D01*
Y-40780D01*
Y-40834D01*
Y-40888D01*
Y-40942D01*
Y-40996D01*
Y-41050D01*
Y-41104D01*
Y-41158D01*
Y-41212D01*
Y-41266D01*
Y-41320D01*
Y-41374D01*
Y-41428D01*
Y-41482D01*
Y-41536D01*
Y-41590D01*
Y-41644D01*
Y-41699D01*
Y-41753D01*
Y-41807D01*
Y-41861D01*
Y-41915D01*
Y-41969D01*
Y-42023D01*
Y-42077D01*
Y-42131D01*
Y-42185D01*
Y-42239D01*
Y-42293D01*
Y-42347D01*
Y-42401D01*
Y-42455D01*
Y-42509D01*
Y-42564D01*
Y-42618D01*
Y-42672D01*
Y-42726D01*
Y-42780D01*
Y-42834D01*
Y-42888D01*
Y-42942D01*
Y-42996D01*
Y-43050D01*
Y-43104D01*
Y-43158D01*
Y-43174D01*
X334879Y-43174D01*
X334902Y-43221D01*
X334919Y-43271D01*
X334929Y-43322D01*
X334933Y-43374D01*
Y-43390D01*
X334933Y-43390D01*
X334956Y-43437D01*
X334973Y-43487D01*
X334981Y-43528D01*
X334988Y-43535D01*
X335003Y-43552D01*
X335032Y-43578D01*
X335057Y-43606D01*
X335086Y-43632D01*
X335111Y-43660D01*
X335140Y-43686D01*
X335165Y-43714D01*
X335194Y-43740D01*
X335219Y-43769D01*
X335248Y-43794D01*
X335267Y-43816D01*
X335273Y-43823D01*
X335281Y-43830D01*
X335302Y-43848D01*
X335327Y-43877D01*
X335356Y-43902D01*
X335381Y-43931D01*
X335410Y-43956D01*
X335435Y-43985D01*
X335464Y-44010D01*
X335489Y-44039D01*
X335518Y-44064D01*
X335543Y-44093D01*
X335562Y-44109D01*
X335572Y-44118D01*
X335598Y-44147D01*
X335623Y-44170D01*
X335626Y-44172D01*
X335652Y-44201D01*
X335680Y-44226D01*
X335706Y-44255D01*
X335735Y-44280D01*
X335760Y-44309D01*
X335788Y-44334D01*
X335814Y-44363D01*
X335843Y-44388D01*
X335868Y-44417D01*
X335897Y-44442D01*
X335922Y-44471D01*
X335951Y-44497D01*
X335976Y-44525D01*
X336005Y-44551D01*
X336030Y-44579D01*
X336059Y-44605D01*
X336084Y-44633D01*
X336110Y-44656D01*
X336113Y-44659D01*
X336138Y-44688D01*
X336167Y-44713D01*
X336192Y-44742D01*
X336221Y-44767D01*
X336246Y-44796D01*
X336275Y-44821D01*
X336300Y-44850D01*
X336329Y-44875D01*
X336354Y-44904D01*
X336383Y-44929D01*
X336396Y-44944D01*
X336410Y-44949D01*
X336415Y-44950D01*
X336462Y-44973D01*
X336463Y-44974D01*
X336478D01*
X336530Y-44977D01*
X336582Y-44987D01*
X336632Y-45004D01*
X336679Y-45028D01*
X336679Y-45028D01*
X343970D01*
Y-44996D01*
Y-44942D01*
Y-44888D01*
Y-44834D01*
Y-44780D01*
Y-44726D01*
Y-44672D01*
Y-44618D01*
Y-44564D01*
Y-44510D01*
Y-44456D01*
Y-44402D01*
Y-44348D01*
Y-44293D01*
Y-44239D01*
Y-44185D01*
Y-44131D01*
Y-44077D01*
Y-44023D01*
Y-43969D01*
Y-43915D01*
Y-43861D01*
Y-43807D01*
Y-43753D01*
Y-43699D01*
Y-43645D01*
Y-43591D01*
Y-43537D01*
Y-43483D01*
Y-43429D01*
Y-43374D01*
Y-43320D01*
Y-43266D01*
Y-43212D01*
Y-43158D01*
Y-43104D01*
Y-43050D01*
Y-42996D01*
Y-42942D01*
Y-42888D01*
Y-42834D01*
Y-42780D01*
Y-42726D01*
Y-42672D01*
Y-42618D01*
Y-42564D01*
Y-42509D01*
Y-42455D01*
Y-42401D01*
Y-42347D01*
Y-42293D01*
Y-42239D01*
Y-42185D01*
Y-42131D01*
Y-42077D01*
Y-42023D01*
Y-41969D01*
Y-41915D01*
Y-41861D01*
Y-41807D01*
Y-41753D01*
Y-41699D01*
Y-41644D01*
Y-41590D01*
Y-41536D01*
Y-41482D01*
Y-41428D01*
Y-41374D01*
Y-41320D01*
Y-41266D01*
Y-41212D01*
Y-41158D01*
Y-41104D01*
Y-41050D01*
Y-40996D01*
Y-40942D01*
Y-40888D01*
Y-40834D01*
Y-40780D01*
Y-40725D01*
Y-40671D01*
Y-40617D01*
Y-40563D01*
Y-40509D01*
Y-40455D01*
Y-40401D01*
Y-40347D01*
Y-40293D01*
Y-40239D01*
Y-40185D01*
Y-40131D01*
Y-40077D01*
Y-40023D01*
Y-39968D01*
Y-39915D01*
Y-39860D01*
Y-39806D01*
Y-39752D01*
Y-39698D01*
Y-39644D01*
Y-39590D01*
Y-39536D01*
Y-39482D01*
Y-39428D01*
Y-39374D01*
Y-39320D01*
Y-39266D01*
Y-39212D01*
Y-39158D01*
Y-39103D01*
Y-39050D01*
Y-38995D01*
Y-38941D01*
Y-38887D01*
Y-38833D01*
Y-38779D01*
Y-38725D01*
Y-38671D01*
Y-38617D01*
Y-38563D01*
Y-38509D01*
Y-38455D01*
Y-38401D01*
Y-38347D01*
Y-38293D01*
Y-38238D01*
Y-38184D01*
Y-38130D01*
Y-38076D01*
Y-38022D01*
Y-37968D01*
Y-37914D01*
Y-37860D01*
Y-37806D01*
Y-37752D01*
Y-37698D01*
Y-37644D01*
Y-37590D01*
Y-37536D01*
Y-37482D01*
Y-37428D01*
Y-37374D01*
Y-37319D01*
Y-37265D01*
Y-37211D01*
Y-37157D01*
Y-37103D01*
Y-37049D01*
Y-36995D01*
Y-36941D01*
Y-36887D01*
Y-36833D01*
Y-36779D01*
Y-36725D01*
Y-36671D01*
Y-36617D01*
Y-36563D01*
Y-36509D01*
Y-36454D01*
Y-36400D01*
Y-36346D01*
Y-36292D01*
Y-36238D01*
Y-36184D01*
Y-36130D01*
Y-36076D01*
Y-36022D01*
Y-35968D01*
Y-35914D01*
Y-35860D01*
Y-35806D01*
Y-35752D01*
Y-35698D01*
Y-35644D01*
Y-35590D01*
Y-35535D01*
Y-35481D01*
Y-35427D01*
Y-35373D01*
Y-35319D01*
Y-35265D01*
Y-35211D01*
Y-35157D01*
Y-35103D01*
Y-35049D01*
Y-34995D01*
Y-34941D01*
Y-34887D01*
Y-34833D01*
Y-34779D01*
Y-34725D01*
Y-34670D01*
Y-34616D01*
Y-34562D01*
Y-34508D01*
Y-34454D01*
Y-34400D01*
Y-34346D01*
Y-34292D01*
Y-34238D01*
Y-34184D01*
Y-34130D01*
Y-34078D01*
X343968Y-34076D01*
X343967Y-34074D01*
X343948Y-34068D01*
X343900Y-34045D01*
X343900Y-34044D01*
D02*
G37*
%LPD*%
G36*
X353074Y-36003D02*
X353125Y-36013D01*
X353175Y-36030D01*
X353222Y-36053D01*
X353265Y-36082D01*
X353305Y-36117D01*
X353339Y-36156D01*
X353368Y-36200D01*
X353392Y-36247D01*
X353408Y-36297D01*
X353419Y-36348D01*
X353422Y-36400D01*
Y-36454D01*
Y-36509D01*
Y-36563D01*
Y-36617D01*
Y-36671D01*
Y-36725D01*
Y-36779D01*
Y-36833D01*
Y-36887D01*
Y-36941D01*
Y-36995D01*
Y-37049D01*
Y-37103D01*
Y-37157D01*
Y-37211D01*
Y-37265D01*
Y-37319D01*
Y-37374D01*
Y-37428D01*
Y-37482D01*
Y-37536D01*
Y-37590D01*
Y-37644D01*
Y-37698D01*
Y-37752D01*
Y-37806D01*
Y-37860D01*
Y-37914D01*
Y-37968D01*
Y-38022D01*
Y-38076D01*
Y-38130D01*
Y-38184D01*
Y-38238D01*
Y-38293D01*
Y-38347D01*
Y-38401D01*
Y-38455D01*
Y-38509D01*
Y-38563D01*
Y-38617D01*
Y-38671D01*
Y-38725D01*
Y-38779D01*
Y-38833D01*
Y-38887D01*
Y-38941D01*
Y-38995D01*
Y-39050D01*
Y-39103D01*
Y-39158D01*
Y-39212D01*
Y-39266D01*
X353419Y-39318D01*
X353408Y-39369D01*
X353392Y-39419D01*
X353368Y-39466D01*
X353339Y-39510D01*
X353305Y-39549D01*
X353265Y-39584D01*
X353222Y-39613D01*
X353175Y-39636D01*
X353125Y-39653D01*
X353074Y-39663D01*
X353021Y-39667D01*
X348967D01*
X348914Y-39663D01*
X348863Y-39653D01*
X348813Y-39636D01*
X348766Y-39613D01*
X348723Y-39584D01*
X348683Y-39549D01*
X348649Y-39510D01*
X348619Y-39466D01*
X348596Y-39419D01*
X348579Y-39369D01*
X348569Y-39318D01*
X348566Y-39266D01*
Y-39212D01*
Y-39158D01*
Y-39103D01*
Y-39050D01*
Y-38995D01*
Y-38941D01*
Y-38887D01*
Y-38833D01*
Y-38779D01*
Y-38725D01*
Y-38671D01*
Y-38617D01*
Y-38563D01*
Y-38509D01*
Y-38455D01*
Y-38401D01*
Y-38347D01*
Y-38293D01*
Y-38238D01*
Y-38184D01*
Y-38130D01*
Y-38076D01*
Y-38022D01*
Y-37968D01*
Y-37914D01*
Y-37860D01*
Y-37806D01*
Y-37752D01*
Y-37698D01*
Y-37644D01*
Y-37590D01*
Y-37536D01*
Y-37482D01*
Y-37428D01*
Y-37374D01*
Y-37319D01*
Y-37265D01*
Y-37211D01*
Y-37157D01*
Y-37103D01*
Y-37049D01*
Y-36995D01*
Y-36941D01*
Y-36887D01*
Y-36833D01*
Y-36779D01*
Y-36725D01*
Y-36671D01*
Y-36617D01*
Y-36563D01*
Y-36509D01*
Y-36454D01*
Y-36400D01*
X348569Y-36348D01*
X348579Y-36297D01*
X348596Y-36247D01*
X348619Y-36200D01*
X348649Y-36156D01*
X348683Y-36117D01*
X348723Y-36082D01*
X348766Y-36053D01*
X348813Y-36030D01*
X348863Y-36013D01*
X348914Y-36003D01*
X348967Y-36000D01*
X353021D01*
X353074Y-36003D01*
D02*
G37*
G36*
X341396Y-36111D02*
X341447Y-36121D01*
X341497Y-36138D01*
X341544Y-36161D01*
X341588Y-36191D01*
X341627Y-36225D01*
X341652Y-36254D01*
X341681Y-36279D01*
X341716Y-36319D01*
X341745Y-36362D01*
X341768Y-36409D01*
X341785Y-36459D01*
X341795Y-36510D01*
X341799Y-36563D01*
Y-36617D01*
Y-36671D01*
Y-36725D01*
Y-36779D01*
Y-36833D01*
Y-36887D01*
Y-36941D01*
Y-36995D01*
Y-37049D01*
Y-37103D01*
Y-37157D01*
Y-37211D01*
Y-37265D01*
Y-37319D01*
Y-37374D01*
Y-37428D01*
Y-37482D01*
Y-37536D01*
Y-37590D01*
Y-37644D01*
Y-37698D01*
Y-37752D01*
Y-37806D01*
Y-37860D01*
Y-37914D01*
Y-37968D01*
Y-38022D01*
Y-38076D01*
Y-38130D01*
Y-38184D01*
Y-38238D01*
Y-38293D01*
Y-38347D01*
Y-38401D01*
Y-38455D01*
Y-38509D01*
Y-38563D01*
Y-38617D01*
Y-38671D01*
Y-38725D01*
Y-38779D01*
Y-38833D01*
Y-38887D01*
Y-38941D01*
Y-38995D01*
Y-39050D01*
Y-39103D01*
Y-39158D01*
Y-39212D01*
Y-39266D01*
Y-39320D01*
Y-39374D01*
Y-39428D01*
Y-39482D01*
Y-39536D01*
Y-39590D01*
Y-39644D01*
Y-39698D01*
Y-39752D01*
Y-39806D01*
Y-39860D01*
Y-39915D01*
Y-39968D01*
Y-40023D01*
Y-40077D01*
Y-40131D01*
Y-40185D01*
Y-40239D01*
Y-40293D01*
Y-40347D01*
Y-40401D01*
Y-40455D01*
Y-40509D01*
Y-40563D01*
Y-40617D01*
Y-40671D01*
Y-40725D01*
Y-40780D01*
Y-40834D01*
Y-40888D01*
Y-40942D01*
Y-40996D01*
Y-41050D01*
Y-41104D01*
Y-41158D01*
Y-41212D01*
Y-41266D01*
Y-41320D01*
Y-41374D01*
Y-41428D01*
Y-41482D01*
Y-41536D01*
Y-41590D01*
Y-41644D01*
Y-41699D01*
Y-41753D01*
Y-41807D01*
Y-41861D01*
Y-41915D01*
Y-41969D01*
Y-42023D01*
Y-42077D01*
Y-42131D01*
Y-42185D01*
Y-42239D01*
Y-42293D01*
Y-42347D01*
Y-42401D01*
Y-42455D01*
Y-42509D01*
Y-42564D01*
X341795Y-42616D01*
X341785Y-42667D01*
X341768Y-42717D01*
X341745Y-42764D01*
X341716Y-42807D01*
X341681Y-42847D01*
X341642Y-42882D01*
X341598Y-42911D01*
X341551Y-42934D01*
X341502Y-42951D01*
X341450Y-42961D01*
X341398Y-42964D01*
X337451D01*
X337399Y-42961D01*
X337348Y-42951D01*
X337298Y-42934D01*
X337251Y-42911D01*
X337207Y-42882D01*
X337168Y-42847D01*
X337133Y-42807D01*
X337104Y-42764D01*
X337081Y-42717D01*
X337064Y-42667D01*
X337054Y-42616D01*
X337051Y-42564D01*
Y-42509D01*
Y-42455D01*
Y-42401D01*
Y-42347D01*
Y-42293D01*
Y-42239D01*
Y-42185D01*
Y-42131D01*
Y-42077D01*
Y-42023D01*
Y-41969D01*
Y-41915D01*
Y-41861D01*
Y-41807D01*
Y-41753D01*
Y-41699D01*
Y-41644D01*
Y-41590D01*
Y-41536D01*
Y-41482D01*
Y-41428D01*
Y-41374D01*
Y-41320D01*
Y-41266D01*
Y-41212D01*
Y-41158D01*
Y-41104D01*
Y-41050D01*
Y-40996D01*
Y-40942D01*
Y-40888D01*
Y-40834D01*
Y-40780D01*
Y-40725D01*
Y-40671D01*
Y-40617D01*
Y-40563D01*
Y-40509D01*
Y-40455D01*
Y-40401D01*
Y-40347D01*
Y-40293D01*
Y-40239D01*
Y-40185D01*
Y-40131D01*
Y-40077D01*
Y-40023D01*
Y-39968D01*
Y-39915D01*
Y-39860D01*
Y-39806D01*
Y-39752D01*
Y-39698D01*
Y-39644D01*
Y-39590D01*
Y-39536D01*
Y-39482D01*
Y-39428D01*
Y-39374D01*
Y-39320D01*
Y-39266D01*
Y-39212D01*
Y-39158D01*
Y-39103D01*
Y-39050D01*
Y-38995D01*
Y-38941D01*
Y-38887D01*
Y-38833D01*
Y-38779D01*
Y-38725D01*
Y-38671D01*
Y-38617D01*
Y-38563D01*
Y-38509D01*
Y-38455D01*
Y-38401D01*
Y-38347D01*
Y-38293D01*
Y-38238D01*
Y-38184D01*
Y-38130D01*
Y-38076D01*
Y-38022D01*
Y-37968D01*
Y-37914D01*
Y-37860D01*
Y-37806D01*
Y-37752D01*
Y-37698D01*
Y-37644D01*
Y-37590D01*
Y-37536D01*
Y-37482D01*
Y-37428D01*
Y-37374D01*
Y-37319D01*
Y-37265D01*
Y-37211D01*
Y-37157D01*
Y-37103D01*
Y-37049D01*
Y-36995D01*
Y-36941D01*
Y-36887D01*
Y-36833D01*
Y-36779D01*
Y-36725D01*
Y-36671D01*
Y-36617D01*
Y-36563D01*
X337054Y-36510D01*
X337064Y-36459D01*
X337081Y-36409D01*
X337104Y-36362D01*
X337133Y-36319D01*
X337168Y-36279D01*
X337207Y-36245D01*
X337251Y-36215D01*
X337298Y-36192D01*
X337328Y-36182D01*
X337359Y-36161D01*
X337406Y-36138D01*
X337456Y-36121D01*
X337507Y-36111D01*
X337560Y-36108D01*
X337614D01*
X337666Y-36111D01*
X337668Y-36112D01*
X337669Y-36111D01*
X337722Y-36108D01*
X337776D01*
X337828Y-36111D01*
X337879Y-36121D01*
X337929Y-36138D01*
X337976Y-36161D01*
X337977Y-36162D01*
X341089D01*
X341089Y-36161D01*
X341136Y-36138D01*
X341186Y-36121D01*
X341237Y-36111D01*
X341290Y-36108D01*
X341344D01*
X341396Y-36111D01*
D02*
G37*
D84*
X118504Y-390698D02*
D03*
D85*
X216142Y-404084D02*
D03*
D126*
X281102Y-401427D02*
D03*
X159055D02*
D03*
X155118D02*
D03*
X186614D02*
D03*
X182677D02*
D03*
X241732D02*
D03*
X273228D02*
D03*
X269291D02*
D03*
X257480D02*
D03*
X237795D02*
D03*
X253543D02*
D03*
X222047D02*
D03*
X218110D02*
D03*
X210236D02*
D03*
X206299D02*
D03*
X190551D02*
D03*
X166929D02*
D03*
X170866D02*
D03*
X174803D02*
D03*
X178740D02*
D03*
X229921D02*
D03*
X214173D02*
D03*
X202362D02*
D03*
X249606D02*
D03*
X265354D02*
D03*
X245669D02*
D03*
X277165D02*
D03*
X261417D02*
D03*
X233858D02*
D03*
X225984D02*
D03*
X162992D02*
D03*
D127*
X151181Y-399477D02*
D03*
D133*
X142362Y-120079D02*
D03*
X152362D02*
D03*
X162362D02*
D03*
X579055Y13937D02*
D03*
X569055D02*
D03*
X559055D02*
D03*
X549055D02*
D03*
X539055D02*
D03*
X589055Y3937D02*
D03*
X579055D02*
D03*
X569055D02*
D03*
X559055D02*
D03*
X549055D02*
D03*
X539055D02*
D03*
D134*
X172362Y-120079D02*
D03*
X589055Y13937D02*
D03*
D135*
X258472Y-327165D02*
D03*
X282283D02*
D03*
X294094D02*
D03*
X302362Y-156693D02*
D03*
Y-316535D02*
D03*
X142520D02*
D03*
Y-236614D02*
D03*
Y-156693D02*
D03*
X270472Y-327165D02*
D03*
X246472D02*
D03*
D136*
X674409Y-194488D02*
D03*
Y-161417D02*
D03*
X348211Y-89891D02*
D03*
X357798Y-89963D02*
D03*
D137*
X645669Y-194488D02*
D03*
X624016D02*
D03*
Y-177953D02*
D03*
X645669D02*
D03*
X624016Y-161417D02*
D03*
X645669D02*
D03*
D138*
X391545Y-160477D02*
D03*
X470285D02*
D03*
X528395Y-194680D02*
D03*
Y-273420D02*
D03*
X470275Y-308597D02*
D03*
X391535D02*
D03*
X340904Y-273410D02*
D03*
Y-194670D02*
D03*
D139*
X533015Y-312764D02*
D03*
X336415Y-155764D02*
D03*
X336515Y-312764D02*
D03*
X533015Y-155764D02*
D03*
D140*
X604291Y-330039D02*
D03*
X574291D02*
D03*
D141*
X-18464Y-326781D02*
D03*
X1535D02*
D03*
Y-306781D02*
D03*
X-18464D02*
D03*
X-18465Y-273630D02*
D03*
X1535D02*
D03*
Y-253630D02*
D03*
X-18465D02*
D03*
Y-220480D02*
D03*
X1535D02*
D03*
Y-200480D02*
D03*
X-18465D02*
D03*
X-18464Y-167332D02*
D03*
X1535D02*
D03*
Y-147332D02*
D03*
X-18464D02*
D03*
D142*
X-8465Y-316781D02*
D03*
X-8465Y-263630D02*
D03*
Y-210480D02*
D03*
X-8465Y-157332D02*
D03*
D143*
X640640Y-33710D02*
D03*
Y-17962D02*
D03*
X82785Y-53986D02*
D03*
Y-69734D02*
D03*
D144*
X0Y0D02*
D03*
X0Y-378395D02*
D03*
X685039Y0D02*
D03*
X685039Y-340551D02*
D03*
X486221Y-340551D02*
D03*
D145*
X416835Y-196581D02*
D03*
X411811Y-196850D02*
D03*
X314658Y-244775D02*
D03*
X315097Y-235081D02*
D03*
X315226Y-230634D02*
D03*
X314864Y-227997D02*
D03*
X314503Y-225180D02*
D03*
D146*
X564896Y-236697D02*
D03*
D147*
X651545Y-95108D02*
D03*
X413356Y7254D02*
D03*
Y-95108D02*
D03*
X651545Y7254D02*
D03*
X71880Y7412D02*
D03*
X310069Y-94950D02*
D03*
Y7412D02*
D03*
X71880Y-94950D02*
D03*
D148*
X99016Y-121653D02*
D03*
X103347D02*
D03*
X107677D02*
D03*
X99016Y-125984D02*
D03*
X103347D02*
D03*
X107677D02*
D03*
X99016Y-130315D02*
D03*
X103347D02*
D03*
X107677D02*
D03*
D176*
X273441Y-382293D02*
D03*
Y-378907D02*
D03*
X206441D02*
D03*
Y-382293D02*
D03*
X210441D02*
D03*
Y-378907D02*
D03*
X218341D02*
D03*
Y-382293D02*
D03*
X222641D02*
D03*
Y-378907D02*
D03*
X237941Y-382293D02*
D03*
Y-378907D02*
D03*
X241941Y-382293D02*
D03*
Y-378907D02*
D03*
X253441Y-382293D02*
D03*
Y-378907D02*
D03*
X256941D02*
D03*
Y-382293D02*
D03*
X269441D02*
D03*
Y-378907D02*
D03*
M02*
